FILE_TYPE = MACRO_DRAWING;
SET COLOR_WIRE YELLOW;
SET COLOR_PROP ORANGE;
SET COLOR_DOT WHITE;
SET COLOR_ARC YELLOW;
SET COLOR_BODY GREEN;
SET COLOR_NOTE PURPLE;
SET PROP_DISPLAY VALUE;
SET PAGE_NUMBER P162;
FORCEADD UNIVERSAL_GND..1
(-2650 -2400);
FORCEPROP 3 LASTPIN (-2650 -2350) SIG_NAME AGND_HSC\g
J 0
(-2640 -2340);
DISPLAY 0.659574 (-2640 -2340);
PAINT MONO (-2640 -2340);
DISPLAY INVISIBLE (-2640 -2340);
FORCEPROP 1 LAST HDL_POWER AGND_HSC
J 1
(-2625 -2475);
DISPLAY 0.723404 (-2625 -2475);
PAINT GREEN (-2625 -2475);
FORCEPROP 2 LAST CDS_LIB pure_quanta_power
J 0
(-2650 -2400);
DISPLAY INVISIBLE (-2650 -2400);
FORCEPROP 1 LAST PATH I1
J 0
(-2575 -2400);
DISPLAY 0.872340 (-2575 -2400);
PAINT AQUA (-2575 -2400);
DISPLAY INVISIBLE (-2575 -2400);
FORCEADD OFFPAGE..4
R 2
(-2050 -1425);
FORCEPROP 2 LAST $XR2 303 
J 0
(-2542 -1425);
DISPLAY 0.638298 (-2542 -1425);
PAINT MONO (-2542 -1425);
FORCEPROP 2 LAST $XR1 302 
J 0
(-2422 -1425);
DISPLAY 0.638298 (-2422 -1425);
PAINT MONO (-2422 -1425);
FORCEPROP 2 LAST $XR0 301 
J 0
(-2302 -1425);
DISPLAY 0.638298 (-2302 -1425);
PAINT MONO (-2302 -1425);
FORCEPROP 2 LAST CDS_LIB standard
J 0
(-2050 -1425);
DISPLAY INVISIBLE (-2050 -1425);
FORCEPROP 1 LAST OFFPAGE TRUE
J 2
(-2375 -1550);
DISPLAY 0.872340 (-2375 -1550);
PAINT GREEN (-2375 -1550);
DISPLAY INVISIBLE (-2375 -1550);
FORCEPROP 1 LAST COMMENT_BODY TRUE
J 2
(-2025 -1525);
DISPLAY 0.872340 (-2025 -1525);
PAINT GREEN (-2025 -1525);
DISPLAY INVISIBLE (-2025 -1525);
FORCEPROP 2 LAST PATH I10
J 0
(-2300 -1375);
DISPLAY 1.021277 (-2300 -1375);
DISPLAY INVISIBLE (-2300 -1375);
FORCEADD Q_RES..1
(-1925 -1250);
FORCEPROP 1 LAST LOCATION PR3912
J 0
(-2250 -1225);
DISPLAY 0.723404 (-2250 -1225);
PAINT AQUA (-2250 -1225);
FORCEPROP 0 LAST $SEC 1
J 0
(-1875 -1175);
DISPLAY 0.680851 (-1875 -1175);
PAINT MONO (-1875 -1175);
DISPLAY INVISIBLE (-1875 -1175);
FORCEPROP 0 LAST CDS_SEC 1
J 0
(-1875 -1175);
DISPLAY 1.021277 (-1875 -1175);
DISPLAY INVISIBLE (-1875 -1175);
FORCEPROP 1 LASTPIN (-2025 -1250) $PN 1
J 0
(-2013 -1238);
DISPLAY 0.787234 (-2013 -1238);
PAINT MONO (-2013 -1238);
FORCEPROP 1 LASTPIN (-1825 -1250) $PN 2
J 0
(-1863 -1238);
DISPLAY 0.787234 (-1863 -1238);
PAINT MONO (-1863 -1238);
FORCEPROP 1 LAST PART_NUMBER CS41202FB05
J 0
(-1775 -1225);
DISPLAY 0.723404 (-1775 -1225);
PAINT WHITE (-1775 -1225);
FORCEPROP 1 LAST PACK_TYPE 0402LF
J 0
(-1800 -1325);
DISPLAY 0.723404 (-1800 -1325);
PAINT SKYBLUE (-1800 -1325);
FORCEPROP 1 LAST MATERIAL CHIP
J 0
(-1875 -1375);
DISPLAY 0.723404 (-1875 -1375);
PAINT SKYBLUE (-1875 -1375);
FORCEPROP 1 LAST TOLERANCE 1%
J 0
(-1900 -1325);
DISPLAY 0.723404 (-1900 -1325);
PAINT SKYBLUE (-1900 -1325);
FORCEPROP 1 LAST VALUE 120K
J 2
(-1950 -1325);
DISPLAY 0.723404 (-1950 -1325);
PAINT SKYBLUE (-1950 -1325);
FORCEPROP 1 LAST WATTAGE 1/16W
J 2
(-1900 -1375);
DISPLAY 0.723404 (-1900 -1375);
PAINT SKYBLUE (-1900 -1375);
FORCEPROP 2 LAST CDS_LIB pure_quanta
J 0
(-1925 -1250);
DISPLAY INVISIBLE (-1925 -1250);
FORCEPROP 1 LAST PATH I11
J 0
(-1975 -1100);
DISPLAY 0.978723 (-1975 -1100);
PAINT WHITE (-1975 -1100);
DISPLAY INVISIBLE (-1975 -1100);
FORCEADD Q_CAP..1
(-1975 -2075);
FORCEPROP 1 LAST LOCATION PC2348
J 0
(-1900 -1975);
DISPLAY 0.638298 (-1900 -1975);
PAINT AQUA (-1900 -1975);
FORCEPROP 0 LAST $SEC 1
J 0
(-1900 -1925);
DISPLAY 0.680851 (-1900 -1925);
PAINT MONO (-1900 -1925);
DISPLAY INVISIBLE (-1900 -1925);
FORCEPROP 0 LAST CDS_SEC 1
J 0
(-1900 -1925);
DISPLAY 1.021277 (-1900 -1925);
DISPLAY INVISIBLE (-1900 -1925);
FORCEPROP 1 LASTPIN (-1975 -1975) $PN 1
J 0
(-1965 -1995);
DISPLAY 0.787234 (-1965 -1995);
PAINT MONO (-1965 -1995);
FORCEPROP 1 LASTPIN (-1975 -2175) $PN 2
J 0
(-1965 -2195);
DISPLAY 0.787234 (-1965 -2195);
PAINT MONO (-1965 -2195);
FORCEPROP 1 LAST PART_NUMBER CH21006KB16
J 0
(-1900 -2175);
DISPLAY 0.723404 (-1900 -2175);
PAINT WHITE (-1900 -2175);
FORCEPROP 1 LAST VALUE 1NF
J 0
(-1900 -2025);
DISPLAY 0.723404 (-1900 -2025);
PAINT SKYBLUE (-1900 -2025);
FORCEPROP 1 LAST VOLTAGE 50V
J 0
(-1900 -2075);
DISPLAY 0.723404 (-1900 -2075);
PAINT SKYBLUE (-1900 -2075);
FORCEPROP 1 LAST MATERIAL EMPTY
J 0
(-1900 -2125);
DISPLAY 0.723404 (-1900 -2125);
PAINT RED (-1900 -2125);
FORCEPROP 1 LAST PACK_TYPE 0402
J 0
(-1900 -2225);
DISPLAY 0.723404 (-1900 -2225);
PAINT SKYBLUE (-1900 -2225);
FORCEPROP 1 LAST TOLERANCE 10%
J 0
(-1925 -2125);
DISPLAY 0.978723 (-1925 -2125);
PAINT SKYBLUE (-1925 -2125);
DISPLAY INVISIBLE (-1925 -2125);
FORCEPROP 2 LAST CDS_LIB pure_quanta
J 0
(-1975 -2075);
DISPLAY INVISIBLE (-1975 -2075);
FORCEPROP 1 LAST PATH I12
J 0
(-1925 -1925);
DISPLAY 0.978723 (-1925 -1925);
PAINT WHITE (-1925 -1925);
DISPLAY INVISIBLE (-1925 -1925);
FORCEADD Q_RES..2
(-1500 -2075);
FORCEPROP 1 LAST LOCATION PR3915
J 0
(-1445 -1925);
DISPLAY 0.723404 (-1445 -1925);
PAINT AQUA (-1445 -1925);
FORCEPROP 0 LAST $SEC 1
J 0
(-1425 -1875);
DISPLAY 0.680851 (-1425 -1875);
PAINT MONO (-1425 -1875);
DISPLAY INVISIBLE (-1425 -1875);
FORCEPROP 0 LAST CDS_SEC 1
J 0
(-1425 -1875);
DISPLAY 1.021277 (-1425 -1875);
DISPLAY INVISIBLE (-1425 -1875);
FORCEPROP 1 LASTPIN (-1500 -1975) $PN 1
J 0
(-1495 -2013);
DISPLAY 0.787234 (-1495 -2013);
PAINT MONO (-1495 -2013);
FORCEPROP 1 LASTPIN (-1500 -2175) $PN 2
J 0
(-1495 -2165);
DISPLAY 0.787234 (-1495 -2165);
PAINT MONO (-1495 -2165);
FORCEPROP 1 LAST VALUE 2K
J 0
(-1445 -1975);
DISPLAY 0.723404 (-1445 -1975);
PAINT SKYBLUE (-1445 -1975);
FORCEPROP 1 LAST TOLERANCE 0.1%
J 0
(-1445 -2025);
DISPLAY 0.723404 (-1445 -2025);
PAINT SKYBLUE (-1445 -2025);
FORCEPROP 1 LAST WATTAGE 1/16W
J 0
(-1450 -2075);
DISPLAY 0.723404 (-1450 -2075);
PAINT SKYBLUE (-1450 -2075);
FORCEPROP 1 LAST PART_NUMBER CS22002BB07
J 0
(-1450 -2175);
DISPLAY 0.723404 (-1450 -2175);
PAINT WHITE (-1450 -2175);
FORCEPROP 1 LAST PACK_TYPE 0402LF
J 0
(-1450 -2225);
DISPLAY 0.723404 (-1450 -2225);
PAINT SKYBLUE (-1450 -2225);
FORCEPROP 1 LAST MATERIAL CHIP
J 0
(-1450 -2125);
DISPLAY 0.723404 (-1450 -2125);
PAINT SKYBLUE (-1450 -2125);
FORCEPROP 2 LAST CDS_LIB pure_quanta
J 0
(-1500 -2075);
DISPLAY INVISIBLE (-1500 -2075);
FORCEPROP 1 LAST PATH I13
J 0
(-1450 -1900);
DISPLAY 0.978723 (-1450 -1900);
PAINT WHITE (-1450 -1900);
DISPLAY INVISIBLE (-1450 -1900);
FORCEADD OFFPAGE..5
(-1075 -1850);
FORCEPROP 2 LAST $XR2 301 
J 0
(-1330 -1814);
DISPLAY 0.638298 (-1330 -1814);
PAINT MONO (-1330 -1814);
FORCEPROP 2 LAST $XR1 303 
J 0
(-1450 -1850);
DISPLAY 0.638298 (-1450 -1850);
PAINT MONO (-1450 -1850);
FORCEPROP 2 LAST $XR0 302 
J 0
(-1330 -1850);
DISPLAY 0.638298 (-1330 -1850);
PAINT MONO (-1330 -1850);
FORCEPROP 2 LAST CDS_LIB standard
J 0
(-1075 -1850);
DISPLAY INVISIBLE (-1075 -1850);
FORCEPROP 1 LAST OFFPAGE TRUE
J 0
(-750 -1975);
DISPLAY 0.872340 (-750 -1975);
PAINT AQUA (-750 -1975);
DISPLAY INVISIBLE (-750 -1975);
FORCEPROP 1 LAST COMMENT_BODY TRUE
J 0
(-975 -1925);
DISPLAY 1.170213 (-975 -1925);
PAINT GREEN (-975 -1925);
DISPLAY INVISIBLE (-975 -1925);
FORCEPROP 2 LAST PATH I14
J 0
(-1325 -1775);
DISPLAY 1.021277 (-1325 -1775);
DISPLAY INVISIBLE (-1325 -1775);
FORCEADD Q_RES..2
(-975 -2075);
FORCEPROP 1 LAST $LOCATION PR1101
J 0
(-920 -1925);
DISPLAY 0.723404 (-920 -1925);
PAINT AQUA (-920 -1925);
FORCEPROP 0 LAST CDS_LOCATION PR1101
J 0
(-900 -1875);
DISPLAY 1.021277 (-900 -1875);
DISPLAY INVISIBLE (-900 -1875);
FORCEPROP 0 LAST $SEC 1
J 0
(-900 -1875);
DISPLAY 0.680851 (-900 -1875);
PAINT MONO (-900 -1875);
DISPLAY INVISIBLE (-900 -1875);
FORCEPROP 0 LAST CDS_SEC 1
J 0
(-900 -1875);
DISPLAY 1.021277 (-900 -1875);
DISPLAY INVISIBLE (-900 -1875);
FORCEPROP 1 LASTPIN (-975 -1975) $PN 1
J 0
(-970 -2013);
DISPLAY 0.787234 (-970 -2013);
PAINT MONO (-970 -2013);
FORCEPROP 1 LASTPIN (-975 -2175) $PN 2
J 0
(-970 -2165);
DISPLAY 0.787234 (-970 -2165);
PAINT MONO (-970 -2165);
FORCEPROP 1 LAST PART_NUMBER CS22002BB07
J 0
(-925 -2175);
DISPLAY 0.723404 (-925 -2175);
PAINT WHITE (-925 -2175);
FORCEPROP 1 LAST PACK_TYPE 0402LF
J 0
(-925 -2225);
DISPLAY 0.723404 (-925 -2225);
PAINT SKYBLUE (-925 -2225);
FORCEPROP 1 LAST TOLERANCE 0.1%
J 0
(-920 -2025);
DISPLAY 0.723404 (-920 -2025);
PAINT SKYBLUE (-920 -2025);
FORCEPROP 1 LAST MATERIAL CHIP
J 0
(-925 -2125);
DISPLAY 0.723404 (-925 -2125);
PAINT SKYBLUE (-925 -2125);
FORCEPROP 1 LAST WATTAGE 1/16W
J 0
(-925 -2075);
DISPLAY 0.723404 (-925 -2075);
PAINT SKYBLUE (-925 -2075);
FORCEPROP 1 LAST VALUE 2K
J 0
(-920 -1975);
DISPLAY 0.723404 (-920 -1975);
PAINT SKYBLUE (-920 -1975);
FORCEPROP 2 LAST CDS_LIB pure_quanta
J 0
(-975 -2075);
DISPLAY INVISIBLE (-975 -2075);
FORCEPROP 1 LAST PATH I15
J 0
(-925 -1900);
DISPLAY 0.978723 (-925 -1900);
PAINT WHITE (-925 -1900);
DISPLAY INVISIBLE (-925 -1900);
FORCEADD MP5991GLUZ..1
(0 -1325);
FORCEPROP 1 LAST LOCATION PU288
J 0
(-320 -244);
DISPLAY 0.723404 (-320 -244);
PAINT GREEN (-320 -244);
FORCEPROP 2 LAST SEC 1
J 0
(-300 -100);
DISPLAY 0.680851 (-300 -100);
PAINT MONO (-300 -100);
DISPLAY INVISIBLE (-300 -100);
FORCEPROP 2 LASTPIN (-475 -1750) $PN 23
J 2
(-485 -1740);
DISPLAY 0.680851 (-485 -1740);
PAINT MONO (-485 -1740);
FORCEPROP 2 LASTPIN (475 -1400) $PN 3
J 0
(485 -1390);
DISPLAY 0.680851 (485 -1390);
PAINT MONO (485 -1390);
FORCEPROP 2 LASTPIN (475 -1500) $PN 6
J 0
(485 -1490);
DISPLAY 0.680851 (485 -1490);
PAINT MONO (485 -1490);
FORCEPROP 2 LASTPIN (-475 -2050) $PN 20
J 2
(-485 -2040);
DISPLAY 0.680851 (-485 -2040);
PAINT MONO (-485 -2040);
FORCEPROP 2 LASTPIN (475 -1700) $PN 5
J 0
(485 -1690);
DISPLAY 0.680851 (485 -1690);
PAINT MONO (485 -1690);
FORCEPROP 2 LASTPIN (-475 -1850) $PN 22
J 2
(-485 -1840);
DISPLAY 0.680851 (-485 -1840);
PAINT MONO (-485 -1840);
FORCEPROP 2 LASTPIN (-475 -1250) $PN 8
J 2
(-485 -1240);
DISPLAY 0.680851 (-485 -1240);
PAINT MONO (-485 -1240);
FORCEPROP 2 LASTPIN (475 -1600) $PN 7
J 0
(485 -1590);
DISPLAY 0.680851 (485 -1590);
PAINT MONO (485 -1590);
FORCEPROP 2 LASTPIN (-475 -1650) $PN 24
J 2
(-485 -1640);
DISPLAY 0.680851 (-485 -1640);
PAINT MONO (-485 -1640);
FORCEPROP 2 LASTPIN (-475 -1550) $PN 4
J 2
(-485 -1540);
DISPLAY 0.680851 (-485 -1540);
PAINT MONO (-485 -1540);
FORCEPROP 2 LASTPIN (-475 -1350) $PN 17
J 2
(-485 -1340);
DISPLAY 0.680851 (-485 -1340);
PAINT MONO (-485 -1340);
FORCEPROP 2 LASTPIN (475 -1900) $PN 19
J 0
(485 -1890);
DISPLAY 0.680851 (485 -1890);
PAINT MONO (485 -1890);
FORCEPROP 2 LASTPIN (-475 -1150) $PN 21
J 2
(-485 -1140);
DISPLAY 0.680851 (-485 -1140);
PAINT MONO (-485 -1140);
FORCEPROP 2 LASTPIN (-475 -600) $PN 9
J 2
(-485 -590);
DISPLAY 0.680851 (-485 -590);
PAINT MONO (-485 -590);
FORCEPROP 2 LASTPIN (-475 -650) $PN 10
J 2
(-485 -640);
DISPLAY 0.680851 (-485 -640);
PAINT MONO (-485 -640);
FORCEPROP 2 LASTPIN (-475 -700) $PN 11
J 2
(-485 -690);
DISPLAY 0.680851 (-485 -690);
PAINT MONO (-485 -690);
FORCEPROP 2 LASTPIN (-475 -750) $PN 12
J 2
(-485 -740);
DISPLAY 0.680851 (-485 -740);
PAINT MONO (-485 -740);
FORCEPROP 2 LASTPIN (-475 -800) $PN 13
J 2
(-485 -790);
DISPLAY 0.680851 (-485 -790);
PAINT MONO (-485 -790);
FORCEPROP 2 LASTPIN (-475 -850) $PN 14
J 2
(-485 -840);
DISPLAY 0.680851 (-485 -840);
PAINT MONO (-485 -840);
FORCEPROP 2 LASTPIN (-475 -900) $PN 15
J 2
(-485 -890);
DISPLAY 0.680851 (-485 -890);
PAINT MONO (-485 -890);
FORCEPROP 2 LASTPIN (-475 -950) $PN 16
J 2
(-485 -940);
DISPLAY 0.680851 (-485 -940);
PAINT MONO (-485 -940);
FORCEPROP 2 LASTPIN (-475 -1000) $PN 33
J 2
(-485 -990);
DISPLAY 0.680851 (-485 -990);
PAINT MONO (-485 -990);
FORCEPROP 2 LASTPIN (475 -600) $PN 1
J 0
(485 -590);
DISPLAY 0.680851 (485 -590);
PAINT MONO (485 -590);
FORCEPROP 2 LASTPIN (475 -650) $PN 2
J 0
(485 -640);
DISPLAY 0.680851 (485 -640);
PAINT MONO (485 -640);
FORCEPROP 2 LASTPIN (475 -700) $PN 25
J 0
(485 -690);
DISPLAY 0.680851 (485 -690);
PAINT MONO (485 -690);
FORCEPROP 2 LASTPIN (475 -750) $PN 26
J 0
(485 -740);
DISPLAY 0.680851 (485 -740);
PAINT MONO (485 -740);
FORCEPROP 2 LASTPIN (475 -800) $PN 27
J 0
(485 -790);
DISPLAY 0.680851 (485 -790);
PAINT MONO (485 -790);
FORCEPROP 2 LASTPIN (475 -850) $PN 28
J 0
(485 -840);
DISPLAY 0.680851 (485 -840);
PAINT MONO (485 -840);
FORCEPROP 2 LASTPIN (475 -900) $PN 29
J 0
(485 -890);
DISPLAY 0.680851 (485 -890);
PAINT MONO (485 -890);
FORCEPROP 2 LASTPIN (475 -950) $PN 30
J 0
(485 -940);
DISPLAY 0.680851 (485 -940);
PAINT MONO (485 -940);
FORCEPROP 2 LASTPIN (475 -1000) $PN 31
J 0
(485 -990);
DISPLAY 0.680851 (485 -990);
PAINT MONO (485 -990);
FORCEPROP 2 LASTPIN (475 -1050) $PN 32
J 0
(485 -1040);
DISPLAY 0.680851 (485 -1040);
PAINT MONO (485 -1040);
FORCEPROP 2 LASTPIN (475 -1800) $PN 18
J 0
(485 -1790);
DISPLAY 0.680851 (485 -1790);
PAINT MONO (485 -1790);
FORCEPROP 2 LAST VALUE MP5991GLU-Z
J 0
(-300 -200);
DISPLAY 1.021277 (-300 -200);
FORCEPROP 1 LAST PART_NUMBER AL005991A00
J 0
(-320 -391);
DISPLAY 0.723404 (-320 -391);
PAINT GREEN (-320 -391);
FORCEPROP 2 LAST PART_TYPE SMLF
J 0
(-300 -150);
DISPLAY 1.021277 (-300 -150);
FORCEPROP 1 LAST MATERIAL IC
J 0
(-320 -518);
DISPLAY 0.723404 (-320 -518);
PAINT GREEN (-320 -518);
FORCEPROP 1 LAST NEEDS_NO_SIZE TRUE
J 0
(0 -1325);
DISPLAY 0.723404 (0 -1325);
PAINT GREEN (0 -1325);
DISPLAY INVISIBLE (0 -1325);
FORCEPROP 1 LAST CDS_LMAN_SYM_OUTLINE -325,775,325,-775
J 0
(0 -1325);
DISPLAY 0.468085 (0 -1325);
PAINT GREEN (0 -1325);
DISPLAY INVISIBLE (0 -1325);
FORCEPROP 2 LAST CDS_LIB pure_quanta
J 0
(0 -1325);
DISPLAY INVISIBLE (0 -1325);
FORCEPROP 2 LAST SEC_TYPE 
J 0
(-300 -100);
DISPLAY 1.021277 (-300 -100);
DISPLAY INVISIBLE (-300 -100);
FORCEPROP 1 LAST PATH I16
J 0
(0 -1325);
DISPLAY 0.723404 (0 -1325);
PAINT GREEN (0 -1325);
DISPLAY INVISIBLE (0 -1325);
FORCEADD Q_RES..1
(-1325 -1425);
FORCEPROP 1 LAST LOCATION PR3917
J 0
(-1625 -1425);
DISPLAY 0.723404 (-1625 -1425);
PAINT AQUA (-1625 -1425);
FORCEPROP 0 LAST $SEC 1
J 0
(-1200 -1350);
DISPLAY 0.680851 (-1200 -1350);
PAINT MONO (-1200 -1350);
DISPLAY INVISIBLE (-1200 -1350);
FORCEPROP 0 LAST CDS_SEC 1
J 0
(-1200 -1350);
DISPLAY 1.021277 (-1200 -1350);
DISPLAY INVISIBLE (-1200 -1350);
FORCEPROP 1 LASTPIN (-1425 -1425) $PN 1
J 0
(-1413 -1413);
DISPLAY 0.787234 (-1413 -1413);
PAINT MONO (-1413 -1413);
FORCEPROP 1 LASTPIN (-1225 -1425) $PN 2
J 0
(-1263 -1413);
DISPLAY 0.787234 (-1263 -1413);
PAINT MONO (-1263 -1413);
FORCEPROP 1 LAST PART_NUMBER CS00002JB13
J 0
(-1650 -1475);
DISPLAY 0.723404 (-1650 -1475);
PAINT WHITE (-1650 -1475);
FORCEPROP 1 LAST PACK_TYPE 0402LF
J 0
(-1400 -1525);
DISPLAY 0.723404 (-1400 -1525);
PAINT SKYBLUE (-1400 -1525);
FORCEPROP 1 LAST VALUE 0
J 2
(-1200 -1400);
DISPLAY 0.723404 (-1200 -1400);
PAINT SKYBLUE (-1200 -1400);
FORCEPROP 1 LAST TOLERANCE 5%
J 0
(-1200 -1475);
DISPLAY 0.723404 (-1200 -1475);
PAINT SKYBLUE (-1200 -1475);
FORCEPROP 1 LAST MATERIAL CHIP
J 0
(-1150 -1525);
DISPLAY 0.723404 (-1150 -1525);
PAINT SKYBLUE (-1150 -1525);
FORCEPROP 1 LAST WATTAGE 1/16W
J 2
(-1450 -1525);
DISPLAY 0.723404 (-1450 -1525);
PAINT SKYBLUE (-1450 -1525);
FORCEPROP 2 LAST CDS_LIB pure_quanta
J 0
(-1325 -1425);
DISPLAY INVISIBLE (-1325 -1425);
FORCEPROP 1 LAST PATH I17
J 0
(-1375 -1275);
DISPLAY 0.978723 (-1375 -1275);
PAINT WHITE (-1375 -1275);
DISPLAY INVISIBLE (-1375 -1275);
FORCEADD UNIVERSAL_POWER..1
(-975 -450);
FORCEPROP 3 LASTPIN (-975 -500) SIG_NAME P12V_PSU\g
J 0
(-965 -490);
DISPLAY 0.659574 (-965 -490);
PAINT MONO (-965 -490);
DISPLAY INVISIBLE (-965 -490);
FORCEPROP 1 LAST HDL_POWER P12V_PSU
J 1
(-975 -400);
DISPLAY 0.723404 (-975 -400);
PAINT GREEN (-975 -400);
FORCEPROP 2 LAST ROOM AUX_SW
J 0
(-975 -350);
DISPLAY 0.617021 (-975 -350);
FORCEPROP 2 LAST BOM_COST MIO_VRD_SB
J 0
(-975 -350);
DISPLAY 0.617021 (-975 -350);
PAINT PURPLE (-975 -350);
DISPLAY INVISIBLE (-975 -350);
FORCEPROP 2 LAST CDS_LIB pure_quanta_power
J 0
(-975 -450);
DISPLAY INVISIBLE (-975 -450);
FORCEPROP 1 LAST PATH I18
J 0
(-925 -425);
DISPLAY 0.872340 (-925 -425);
PAINT AQUA (-925 -425);
DISPLAY INVISIBLE (-925 -425);
FORCEADD UNIVERSAL_GND..1
(-3450 1075);
FORCEPROP 3 LASTPIN (-3450 1125) SIG_NAME AGND_HSC\g
J 0
(-3440 1135);
DISPLAY 0.659574 (-3440 1135);
PAINT MONO (-3440 1135);
DISPLAY INVISIBLE (-3440 1135);
FORCEPROP 1 LAST HDL_POWER AGND_HSC
J 1
(-3425 1000);
DISPLAY 0.723404 (-3425 1000);
PAINT GREEN (-3425 1000);
FORCEPROP 2 LAST CDS_LIB pure_quanta_power
J 0
(-3450 1075);
DISPLAY INVISIBLE (-3450 1075);
FORCEPROP 1 LAST PATH I19
J 0
(-3375 1075);
DISPLAY 0.872340 (-3375 1075);
PAINT AQUA (-3375 1075);
DISPLAY INVISIBLE (-3375 1075);
FORCEADD Q_CAP..1
(-2650 -2075);
FORCEPROP 1 LAST LOCATION PC2183
J 0
(-2575 -1975);
DISPLAY 0.723404 (-2575 -1975);
PAINT AQUA (-2575 -1975);
FORCEPROP 0 LAST $SEC 1
J 0
(-2575 -1925);
DISPLAY 0.680851 (-2575 -1925);
PAINT MONO (-2575 -1925);
DISPLAY INVISIBLE (-2575 -1925);
FORCEPROP 0 LAST CDS_SEC 1
J 0
(-2575 -1925);
DISPLAY 1.021277 (-2575 -1925);
DISPLAY INVISIBLE (-2575 -1925);
FORCEPROP 1 LASTPIN (-2650 -1975) $PN 1
J 0
(-2640 -1995);
DISPLAY 0.787234 (-2640 -1995);
PAINT MONO (-2640 -1995);
FORCEPROP 1 LASTPIN (-2650 -2175) $PN 2
J 0
(-2640 -2195);
DISPLAY 0.787234 (-2640 -2195);
PAINT MONO (-2640 -2195);
FORCEPROP 1 LAST PART_NUMBER TMP_QCH12206KB14
J 0
(-2575 -2175);
DISPLAY 0.723404 (-2575 -2175);
PAINT WHITE (-2575 -2175);
FORCEPROP 1 LAST PACK_TYPE 0402
J 0
(-2575 -2225);
DISPLAY 0.723404 (-2575 -2225);
PAINT SKYBLUE (-2575 -2225);
FORCEPROP 1 LAST VALUE 220PF
J 0
(-2575 -2025);
DISPLAY 0.723404 (-2575 -2025);
PAINT SKYBLUE (-2575 -2025);
FORCEPROP 1 LAST VOLTAGE 50V
J 0
(-2575 -2075);
DISPLAY 0.723404 (-2575 -2075);
PAINT SKYBLUE (-2575 -2075);
FORCEPROP 1 LAST MATERIAL EMPTY
J 0
(-2575 -2125);
DISPLAY 0.723404 (-2575 -2125);
PAINT RED (-2575 -2125);
FORCEPROP 2 LAST CDS_LIB pure_quanta
J 0
(-2650 -2075);
DISPLAY INVISIBLE (-2650 -2075);
FORCEPROP 1 LAST TOLERANCE 10%
J 0
(-2600 -2125);
DISPLAY 0.978723 (-2600 -2125);
PAINT SKYBLUE (-2600 -2125);
DISPLAY INVISIBLE (-2600 -2125);
FORCEPROP 1 LAST PATH I2
J 0
(-2600 -1925);
DISPLAY 0.978723 (-2600 -1925);
PAINT WHITE (-2600 -1925);
DISPLAY INVISIBLE (-2600 -1925);
FORCEADD Q_CAP..1
(-3450 1375);
FORCEPROP 1 LAST LOCATION PC1525
J 0
(-3375 1525);
DISPLAY 0.723404 (-3375 1525);
PAINT AQUA (-3375 1525);
FORCEPROP 0 LAST $SEC 1
J 0
(-3375 1575);
DISPLAY 0.680851 (-3375 1575);
PAINT MONO (-3375 1575);
DISPLAY INVISIBLE (-3375 1575);
FORCEPROP 0 LAST CDS_SEC 1
J 0
(-3375 1575);
DISPLAY 1.021277 (-3375 1575);
DISPLAY INVISIBLE (-3375 1575);
FORCEPROP 1 LASTPIN (-3450 1475) $PN 1
J 0
(-3440 1455);
DISPLAY 0.787234 (-3440 1455);
PAINT MONO (-3440 1455);
FORCEPROP 1 LASTPIN (-3450 1275) $PN 2
J 0
(-3440 1255);
DISPLAY 0.787234 (-3440 1255);
PAINT MONO (-3440 1255);
FORCEPROP 1 LAST VALUE 1UF
J 0
(-3375 1475);
DISPLAY 0.723404 (-3375 1475);
PAINT SKYBLUE (-3375 1475);
FORCEPROP 1 LAST VOLTAGE 25V
J 0
(-3375 1425);
DISPLAY 0.723404 (-3375 1425);
PAINT SKYBLUE (-3375 1425);
FORCEPROP 1 LAST PART_NUMBER CH5104KEB02
J 0
(-3375 1325);
DISPLAY 0.723404 (-3375 1325);
PAINT WHITE (-3375 1325);
FORCEPROP 1 LAST MATERIAL X6S
J 0
(-3375 1375);
DISPLAY 0.723404 (-3375 1375);
PAINT SKYBLUE (-3375 1375);
FORCEPROP 1 LAST PACK_TYPE C0402
J 0
(-3375 1275);
DISPLAY 0.723404 (-3375 1275);
PAINT SKYBLUE (-3375 1275);
FORCEPROP 2 LAST CDS_LIB pure_quanta
J 0
(-3450 1375);
DISPLAY INVISIBLE (-3450 1375);
FORCEPROP 1 LAST TOLERANCE 10%
J 0
(-3400 1325);
DISPLAY 0.978723 (-3400 1325);
PAINT SKYBLUE (-3400 1325);
DISPLAY INVISIBLE (-3400 1325);
FORCEPROP 1 LAST PATH I20
J 0
(-3400 1525);
DISPLAY 0.978723 (-3400 1525);
PAINT WHITE (-3400 1525);
DISPLAY INVISIBLE (-3400 1525);
FORCEADD Q_RES..1
R 1
(-3450 1850);
FORCEPROP 1 LAST LOCATION PR3910
J 0
(-3375 2000);
DISPLAY 0.723404 (-3375 2000);
PAINT AQUA (-3375 2000);
FORCEPROP 0 LAST $SEC 1
R 1
J 0
(-3375 2050);
DISPLAY 0.680851 (-3375 2050);
PAINT MONO (-3375 2050);
DISPLAY INVISIBLE (-3375 2050);
FORCEPROP 0 LAST CDS_SEC 1
R 1
J 0
(-3375 2050);
DISPLAY 1.021277 (-3375 2050);
DISPLAY INVISIBLE (-3375 2050);
FORCEPROP 1 LASTPIN (-3450 1750) $PN 1
R 1
J 0
(-3462 1762);
DISPLAY 0.787234 (-3462 1762);
PAINT MONO (-3462 1762);
FORCEPROP 1 LASTPIN (-3450 1950) $PN 2
R 1
J 0
(-3462 1912);
DISPLAY 0.787234 (-3462 1912);
PAINT MONO (-3462 1912);
FORCEPROP 1 LAST WATTAGE 1/16W
J 0
(-3375 1800);
DISPLAY 0.723404 (-3375 1800);
PAINT SKYBLUE (-3375 1800);
FORCEPROP 1 LAST PACK_TYPE 0402LF
J 0
(-3375 1700);
DISPLAY 0.723404 (-3375 1700);
PAINT SKYBLUE (-3375 1700);
FORCEPROP 1 LAST MATERIAL CHIP
J 0
(-3375 1850);
DISPLAY 0.787234 (-3375 1850);
PAINT SKYBLUE (-3375 1850);
FORCEPROP 1 LAST TOLERANCE 5%
J 0
(-3375 1900);
DISPLAY 0.723404 (-3375 1900);
PAINT SKYBLUE (-3375 1900);
FORCEPROP 1 LAST VALUE 0
R 2
J 0
(-3350 1975);
DISPLAY 0.723404 (-3350 1975);
PAINT SKYBLUE (-3350 1975);
FORCEPROP 1 LAST PART_NUMBER CS00002JB13
J 0
(-3375 1750);
DISPLAY 0.723404 (-3375 1750);
PAINT WHITE (-3375 1750);
FORCEPROP 2 LAST CDS_LIB pure_quanta
J 0
(-3450 1850);
DISPLAY INVISIBLE (-3450 1850);
FORCEPROP 1 LAST PATH I21
R 1
J 0
(-3600 1800);
DISPLAY 0.978723 (-3600 1800);
PAINT WHITE (-3600 1800);
DISPLAY INVISIBLE (-3600 1800);
FORCEADD UNIVERSAL_POWER..1
(-3450 2100);
FORCEPROP 3 LASTPIN (-3450 2050) SIG_NAME HSC_VDD\g
J 0
(-3440 2060);
DISPLAY 0.659574 (-3440 2060);
PAINT MONO (-3440 2060);
DISPLAY INVISIBLE (-3440 2060);
FORCEPROP 1 LAST HDL_POWER HSC_VDD
J 1
(-3450 2150);
DISPLAY 0.723404 (-3450 2150);
PAINT GREEN (-3450 2150);
FORCEPROP 2 LAST ROOM AUX_SW
J 0
(-3450 2200);
DISPLAY 0.617021 (-3450 2200);
FORCEPROP 2 LAST CDS_LIB pure_quanta_power
J 0
(-3450 2100);
DISPLAY INVISIBLE (-3450 2100);
FORCEPROP 2 LAST BOM_COST MIO_VRD_SB
J 0
(-3450 2200);
DISPLAY 0.617021 (-3450 2200);
PAINT PURPLE (-3450 2200);
DISPLAY INVISIBLE (-3450 2200);
FORCEPROP 1 LAST PATH I22
J 0
(-3400 2125);
DISPLAY 0.872340 (-3400 2125);
PAINT AQUA (-3400 2125);
DISPLAY INVISIBLE (-3400 2125);
FORCEADD UNIVERSAL_GND..1
(-2675 425);
FORCEPROP 3 LASTPIN (-2675 475) SIG_NAME AGND_HSC\g
J 0
(-2665 485);
DISPLAY 0.659574 (-2665 485);
PAINT MONO (-2665 485);
DISPLAY INVISIBLE (-2665 485);
FORCEPROP 1 LAST HDL_POWER AGND_HSC
J 1
(-2650 350);
DISPLAY 0.723404 (-2650 350);
PAINT GREEN (-2650 350);
FORCEPROP 2 LAST CDS_LIB pure_quanta_power
J 0
(-2675 425);
DISPLAY INVISIBLE (-2675 425);
FORCEPROP 1 LAST PATH I23
J 0
(-2600 425);
DISPLAY 0.872340 (-2600 425);
PAINT AQUA (-2600 425);
DISPLAY INVISIBLE (-2600 425);
FORCEADD Q_CAP..1
(-2675 725);
FORCEPROP 1 LAST LOCATION PC2182
J 0
(-2600 825);
DISPLAY 0.723404 (-2600 825);
PAINT AQUA (-2600 825);
FORCEPROP 0 LAST $SEC 1
J 0
(-2600 875);
DISPLAY 0.680851 (-2600 875);
PAINT MONO (-2600 875);
DISPLAY INVISIBLE (-2600 875);
FORCEPROP 0 LAST CDS_SEC 1
J 0
(-2600 875);
DISPLAY 1.021277 (-2600 875);
DISPLAY INVISIBLE (-2600 875);
FORCEPROP 1 LASTPIN (-2675 825) $PN 1
J 0
(-2665 805);
DISPLAY 0.787234 (-2665 805);
PAINT MONO (-2665 805);
FORCEPROP 1 LASTPIN (-2675 625) $PN 2
J 0
(-2665 605);
DISPLAY 0.787234 (-2665 605);
PAINT MONO (-2665 605);
FORCEPROP 1 LAST MATERIAL X7R
J 0
(-2600 675);
DISPLAY 0.723404 (-2600 675);
PAINT SKYBLUE (-2600 675);
FORCEPROP 1 LAST PART_NUMBER TMP_QCH12206KB14
J 0
(-2600 625);
DISPLAY 0.723404 (-2600 625);
PAINT WHITE (-2600 625);
FORCEPROP 1 LAST PACK_TYPE 0402
J 0
(-2600 575);
DISPLAY 0.723404 (-2600 575);
PAINT SKYBLUE (-2600 575);
FORCEPROP 1 LAST VALUE 220PF
J 0
(-2600 775);
DISPLAY 0.723404 (-2600 775);
PAINT SKYBLUE (-2600 775);
FORCEPROP 1 LAST VOLTAGE 50V
J 0
(-2600 725);
DISPLAY 0.723404 (-2600 725);
PAINT SKYBLUE (-2600 725);
FORCEPROP 1 LAST TOLERANCE 10%
J 0
(-2625 675);
DISPLAY 0.978723 (-2625 675);
PAINT SKYBLUE (-2625 675);
DISPLAY INVISIBLE (-2625 675);
FORCEPROP 2 LAST CDS_LIB pure_quanta
J 0
(-2675 725);
DISPLAY INVISIBLE (-2675 725);
FORCEPROP 1 LAST PATH I24
J 0
(-2625 875);
DISPLAY 0.978723 (-2625 875);
PAINT WHITE (-2625 875);
DISPLAY INVISIBLE (-2625 875);
FORCEADD OFFPAGE..4
R 2
(-2150 1150);
FORCEPROP 2 LAST $XR2 303 
J 0
(-2642 1150);
DISPLAY 0.638298 (-2642 1150);
PAINT MONO (-2642 1150);
FORCEPROP 2 LAST $XR1 302 
J 0
(-2522 1150);
DISPLAY 0.638298 (-2522 1150);
PAINT MONO (-2522 1150);
FORCEPROP 2 LAST $XR0 301 
J 0
(-2402 1150);
DISPLAY 0.638298 (-2402 1150);
PAINT MONO (-2402 1150);
FORCEPROP 2 LAST CDS_LIB standard
J 0
(-2150 1150);
DISPLAY INVISIBLE (-2150 1150);
FORCEPROP 1 LAST OFFPAGE TRUE
J 2
(-2475 1025);
DISPLAY 0.872340 (-2475 1025);
PAINT GREEN (-2475 1025);
DISPLAY INVISIBLE (-2475 1025);
FORCEPROP 1 LAST COMMENT_BODY TRUE
J 2
(-2125 1050);
DISPLAY 0.872340 (-2125 1050);
PAINT GREEN (-2125 1050);
DISPLAY INVISIBLE (-2125 1050);
FORCEPROP 2 LAST PATH I25
J 0
(-2400 1200);
DISPLAY 1.021277 (-2400 1200);
DISPLAY INVISIBLE (-2400 1200);
FORCEADD OFFPAGE..4
R 2
(-2775 1250);
FORCEPROP 2 LAST $XR2 303 
J 0
(-3057 1214);
DISPLAY 0.638298 (-3057 1214);
PAINT MONO (-3057 1214);
FORCEPROP 2 LAST $XR1 302 
J 0
(-3177 1250);
DISPLAY 0.638298 (-3177 1250);
PAINT MONO (-3177 1250);
FORCEPROP 2 LAST $XR0 301 
J 0
(-3057 1250);
DISPLAY 0.638298 (-3057 1250);
PAINT MONO (-3057 1250);
FORCEPROP 2 LAST CDS_LIB standard
J 0
(-2775 1250);
DISPLAY INVISIBLE (-2775 1250);
FORCEPROP 1 LAST OFFPAGE TRUE
J 2
(-3100 1125);
DISPLAY 0.872340 (-3100 1125);
PAINT GREEN (-3100 1125);
DISPLAY INVISIBLE (-3100 1125);
FORCEPROP 1 LAST COMMENT_BODY TRUE
J 2
(-2750 1150);
DISPLAY 0.872340 (-2750 1150);
PAINT GREEN (-2750 1150);
DISPLAY INVISIBLE (-2750 1150);
FORCEPROP 2 LAST PATH I26
J 0
(-3050 1300);
DISPLAY 1.021277 (-3050 1300);
DISPLAY INVISIBLE (-3050 1300);
FORCEADD UNIVERSAL_GND..1
(-2625 1475);
FORCEPROP 3 LASTPIN (-2625 1525) SIG_NAME AGND_HSC\g
J 0
(-2615 1535);
DISPLAY 0.659574 (-2615 1535);
PAINT MONO (-2615 1535);
DISPLAY INVISIBLE (-2615 1535);
FORCEPROP 1 LAST HDL_POWER AGND_HSC
J 1
(-2600 1400);
DISPLAY 0.723404 (-2600 1400);
PAINT GREEN (-2600 1400);
FORCEPROP 2 LAST CDS_LIB pure_quanta_power
J 0
(-2625 1475);
DISPLAY INVISIBLE (-2625 1475);
FORCEPROP 1 LAST PATH I27
J 0
(-2550 1475);
DISPLAY 0.872340 (-2550 1475);
PAINT AQUA (-2550 1475);
DISPLAY INVISIBLE (-2550 1475);
FORCEADD OFFPAGE..4
R 2
(-2050 1375);
FORCEPROP 2 LAST $XR2 303 
J 0
(-2542 1375);
DISPLAY 0.638298 (-2542 1375);
PAINT MONO (-2542 1375);
FORCEPROP 2 LAST $XR1 302 
J 0
(-2422 1375);
DISPLAY 0.638298 (-2422 1375);
PAINT MONO (-2422 1375);
FORCEPROP 2 LAST $XR0 301 
J 0
(-2302 1375);
DISPLAY 0.638298 (-2302 1375);
PAINT MONO (-2302 1375);
FORCEPROP 2 LAST CDS_LIB standard
J 0
(-2050 1375);
DISPLAY INVISIBLE (-2050 1375);
FORCEPROP 1 LAST OFFPAGE TRUE
J 2
(-2375 1250);
DISPLAY 0.872340 (-2375 1250);
PAINT GREEN (-2375 1250);
DISPLAY INVISIBLE (-2375 1250);
FORCEPROP 1 LAST COMMENT_BODY TRUE
J 2
(-2025 1275);
DISPLAY 0.872340 (-2025 1275);
PAINT GREEN (-2025 1275);
DISPLAY INVISIBLE (-2025 1275);
FORCEPROP 2 LAST PATH I28
J 0
(-2300 1425);
DISPLAY 1.021277 (-2300 1425);
DISPLAY INVISIBLE (-2300 1425);
FORCEADD Q_RES..1
(-1925 1550);
FORCEPROP 1 LAST $LOCATION PR1134
J 0
(-2200 1575);
DISPLAY 0.723404 (-2200 1575);
PAINT AQUA (-2200 1575);
FORCEPROP 0 LAST CDS_LOCATION PR1134
J 0
(-1875 1625);
DISPLAY 1.021277 (-1875 1625);
DISPLAY INVISIBLE (-1875 1625);
FORCEPROP 0 LAST $SEC 1
J 0
(-1875 1625);
DISPLAY 0.680851 (-1875 1625);
PAINT MONO (-1875 1625);
DISPLAY INVISIBLE (-1875 1625);
FORCEPROP 0 LAST CDS_SEC 1
J 0
(-1875 1625);
DISPLAY 1.021277 (-1875 1625);
DISPLAY INVISIBLE (-1875 1625);
FORCEPROP 1 LASTPIN (-2025 1550) $PN 1
J 0
(-2013 1562);
DISPLAY 0.787234 (-2013 1562);
PAINT MONO (-2013 1562);
FORCEPROP 1 LASTPIN (-1825 1550) $PN 2
J 0
(-1863 1562);
DISPLAY 0.787234 (-1863 1562);
PAINT MONO (-1863 1562);
FORCEPROP 1 LAST PACK_TYPE 0402LF
J 0
(-1800 1475);
DISPLAY 0.723404 (-1800 1475);
PAINT SKYBLUE (-1800 1475);
FORCEPROP 1 LAST TOLERANCE 1%
J 0
(-1900 1475);
DISPLAY 0.723404 (-1900 1475);
PAINT SKYBLUE (-1900 1475);
FORCEPROP 1 LAST MATERIAL CHIP
J 0
(-1875 1425);
DISPLAY 0.723404 (-1875 1425);
PAINT SKYBLUE (-1875 1425);
FORCEPROP 1 LAST VALUE 120K
J 2
(-1950 1475);
DISPLAY 0.723404 (-1950 1475);
PAINT SKYBLUE (-1950 1475);
FORCEPROP 1 LAST PART_NUMBER CS41202FB05
J 0
(-1775 1575);
DISPLAY 0.723404 (-1775 1575);
PAINT WHITE (-1775 1575);
FORCEPROP 1 LAST WATTAGE 1/16W
J 2
(-1900 1425);
DISPLAY 0.723404 (-1900 1425);
PAINT SKYBLUE (-1900 1425);
FORCEPROP 2 LAST CDS_LIB pure_quanta
J 0
(-1925 1550);
DISPLAY INVISIBLE (-1925 1550);
FORCEPROP 1 LAST PATH I29
J 0
(-1975 1700);
DISPLAY 0.978723 (-1975 1700);
PAINT WHITE (-1975 1700);
DISPLAY INVISIBLE (-1975 1700);
FORCEADD UNIVERSAL_GND..1
(-3475 -1725);
FORCEPROP 3 LASTPIN (-3475 -1675) SIG_NAME AGND_HSC\g
J 0
(-3465 -1665);
DISPLAY 0.659574 (-3465 -1665);
PAINT MONO (-3465 -1665);
DISPLAY INVISIBLE (-3465 -1665);
FORCEPROP 1 LAST HDL_POWER AGND_HSC
J 1
(-3450 -1800);
DISPLAY 0.723404 (-3450 -1800);
PAINT GREEN (-3450 -1800);
FORCEPROP 2 LAST CDS_LIB pure_quanta_power
J 0
(-3475 -1725);
DISPLAY INVISIBLE (-3475 -1725);
FORCEPROP 1 LAST PATH I3
J 0
(-3400 -1725);
DISPLAY 0.872340 (-3400 -1725);
PAINT AQUA (-3400 -1725);
DISPLAY INVISIBLE (-3400 -1725);
FORCEADD Q_CAP..1
(-2000 725);
FORCEPROP 1 LAST LOCATION PC2347
J 0
(-1925 825);
DISPLAY 0.723404 (-1925 825);
PAINT AQUA (-1925 825);
FORCEPROP 0 LAST $SEC 1
J 0
(-1925 875);
DISPLAY 0.680851 (-1925 875);
PAINT MONO (-1925 875);
DISPLAY INVISIBLE (-1925 875);
FORCEPROP 0 LAST CDS_SEC 1
J 0
(-1925 875);
DISPLAY 1.021277 (-1925 875);
DISPLAY INVISIBLE (-1925 875);
FORCEPROP 1 LASTPIN (-2000 825) $PN 1
J 0
(-1990 805);
DISPLAY 0.787234 (-1990 805);
PAINT MONO (-1990 805);
FORCEPROP 1 LASTPIN (-2000 625) $PN 2
J 0
(-1990 605);
DISPLAY 0.787234 (-1990 605);
PAINT MONO (-1990 605);
FORCEPROP 1 LAST PACK_TYPE 0402
J 0
(-1925 575);
DISPLAY 0.723404 (-1925 575);
PAINT SKYBLUE (-1925 575);
FORCEPROP 1 LAST MATERIAL EMPTY
J 0
(-1925 675);
DISPLAY 0.723404 (-1925 675);
PAINT RED (-1925 675);
FORCEPROP 1 LAST VOLTAGE 50V
J 0
(-1925 725);
DISPLAY 0.723404 (-1925 725);
PAINT SKYBLUE (-1925 725);
FORCEPROP 1 LAST VALUE 1NF
J 0
(-1925 775);
DISPLAY 0.723404 (-1925 775);
PAINT SKYBLUE (-1925 775);
FORCEPROP 1 LAST PART_NUMBER CH21006KB16
J 0
(-1925 625);
DISPLAY 0.723404 (-1925 625);
PAINT WHITE (-1925 625);
FORCEPROP 1 LAST TOLERANCE 10%
J 0
(-1950 675);
DISPLAY 0.978723 (-1950 675);
PAINT SKYBLUE (-1950 675);
DISPLAY INVISIBLE (-1950 675);
FORCEPROP 2 LAST CDS_LIB pure_quanta
J 0
(-2000 725);
DISPLAY INVISIBLE (-2000 725);
FORCEPROP 1 LAST PATH I30
J 0
(-1950 875);
DISPLAY 0.978723 (-1950 875);
PAINT WHITE (-1950 875);
DISPLAY INVISIBLE (-1950 875);
FORCEADD Q_RES..2
(-1500 725);
FORCEPROP 1 LAST LOCATION PR3914
J 0
(-1445 875);
DISPLAY 0.723404 (-1445 875);
PAINT AQUA (-1445 875);
FORCEPROP 0 LAST $SEC 1
J 0
(-1425 925);
DISPLAY 0.680851 (-1425 925);
PAINT MONO (-1425 925);
DISPLAY INVISIBLE (-1425 925);
FORCEPROP 0 LAST CDS_SEC 1
J 0
(-1425 925);
DISPLAY 1.021277 (-1425 925);
DISPLAY INVISIBLE (-1425 925);
FORCEPROP 1 LASTPIN (-1500 825) $PN 1
J 0
(-1495 787);
DISPLAY 0.787234 (-1495 787);
PAINT MONO (-1495 787);
FORCEPROP 1 LASTPIN (-1500 625) $PN 2
J 0
(-1495 635);
DISPLAY 0.787234 (-1495 635);
PAINT MONO (-1495 635);
FORCEPROP 1 LAST PACK_TYPE 0402LF
J 0
(-1450 575);
DISPLAY 0.723404 (-1450 575);
PAINT SKYBLUE (-1450 575);
FORCEPROP 1 LAST PART_NUMBER CS22002BB07
J 0
(-1450 625);
DISPLAY 0.723404 (-1450 625);
PAINT WHITE (-1450 625);
FORCEPROP 1 LAST MATERIAL CHIP
J 0
(-1450 675);
DISPLAY 0.723404 (-1450 675);
PAINT SKYBLUE (-1450 675);
FORCEPROP 1 LAST WATTAGE 1/16W
J 0
(-1450 725);
DISPLAY 0.723404 (-1450 725);
PAINT SKYBLUE (-1450 725);
FORCEPROP 1 LAST TOLERANCE 0.1%
J 0
(-1445 775);
DISPLAY 0.723404 (-1445 775);
PAINT SKYBLUE (-1445 775);
FORCEPROP 1 LAST VALUE 2K
J 0
(-1445 825);
DISPLAY 0.723404 (-1445 825);
PAINT SKYBLUE (-1445 825);
FORCEPROP 2 LAST CDS_LIB pure_quanta
J 0
(-1500 725);
DISPLAY INVISIBLE (-1500 725);
FORCEPROP 1 LAST PATH I31
J 0
(-1450 900);
DISPLAY 0.978723 (-1450 900);
PAINT WHITE (-1450 900);
DISPLAY INVISIBLE (-1450 900);
FORCEADD OFFPAGE..5
(-1075 950);
FORCEPROP 2 LAST $XR2 301 
J 0
(-1330 986);
DISPLAY 0.638298 (-1330 986);
PAINT MONO (-1330 986);
FORCEPROP 2 LAST $XR1 303 
J 0
(-1450 950);
DISPLAY 0.638298 (-1450 950);
PAINT MONO (-1450 950);
FORCEPROP 2 LAST $XR0 302 
J 0
(-1330 950);
DISPLAY 0.638298 (-1330 950);
PAINT MONO (-1330 950);
FORCEPROP 2 LAST CDS_LIB standard
J 0
(-1075 950);
DISPLAY INVISIBLE (-1075 950);
FORCEPROP 1 LAST OFFPAGE TRUE
J 0
(-750 825);
DISPLAY 0.872340 (-750 825);
PAINT AQUA (-750 825);
DISPLAY INVISIBLE (-750 825);
FORCEPROP 1 LAST COMMENT_BODY TRUE
J 0
(-975 875);
DISPLAY 1.170213 (-975 875);
PAINT GREEN (-975 875);
DISPLAY INVISIBLE (-975 875);
FORCEPROP 2 LAST PATH I32
J 0
(-1325 1025);
DISPLAY 1.021277 (-1325 1025);
DISPLAY INVISIBLE (-1325 1025);
FORCEADD Q_RES..1
(-1350 1375);
FORCEPROP 1 LAST LOCATION PR3916
J 0
(-1650 1375);
DISPLAY 0.723404 (-1650 1375);
PAINT AQUA (-1650 1375);
FORCEPROP 0 LAST $SEC 1
J 0
(-1225 1450);
DISPLAY 0.680851 (-1225 1450);
PAINT MONO (-1225 1450);
DISPLAY INVISIBLE (-1225 1450);
FORCEPROP 0 LAST CDS_SEC 1
J 0
(-1225 1450);
DISPLAY 1.021277 (-1225 1450);
DISPLAY INVISIBLE (-1225 1450);
FORCEPROP 1 LASTPIN (-1450 1375) $PN 1
J 0
(-1438 1387);
DISPLAY 0.787234 (-1438 1387);
PAINT MONO (-1438 1387);
FORCEPROP 1 LASTPIN (-1250 1375) $PN 2
J 0
(-1288 1387);
DISPLAY 0.787234 (-1288 1387);
PAINT MONO (-1288 1387);
FORCEPROP 1 LAST WATTAGE 1/16W
J 2
(-1475 1275);
DISPLAY 0.723404 (-1475 1275);
PAINT SKYBLUE (-1475 1275);
FORCEPROP 1 LAST MATERIAL CHIP
J 0
(-1175 1275);
DISPLAY 0.723404 (-1175 1275);
PAINT SKYBLUE (-1175 1275);
FORCEPROP 1 LAST PACK_TYPE 0402LF
J 0
(-1425 1275);
DISPLAY 0.723404 (-1425 1275);
PAINT SKYBLUE (-1425 1275);
FORCEPROP 1 LAST TOLERANCE 5%
J 0
(-1225 1325);
DISPLAY 0.723404 (-1225 1325);
PAINT SKYBLUE (-1225 1325);
FORCEPROP 1 LAST VALUE 0
J 2
(-1200 1400);
DISPLAY 0.723404 (-1200 1400);
PAINT SKYBLUE (-1200 1400);
FORCEPROP 1 LAST PART_NUMBER CS00002JB13
J 0
(-1675 1325);
DISPLAY 0.723404 (-1675 1325);
PAINT WHITE (-1675 1325);
FORCEPROP 2 LAST CDS_LIB pure_quanta
J 0
(-1350 1375);
DISPLAY INVISIBLE (-1350 1375);
FORCEPROP 1 LAST PATH I33
J 0
(-1400 1525);
DISPLAY 0.978723 (-1400 1525);
PAINT WHITE (-1400 1525);
DISPLAY INVISIBLE (-1400 1525);
FORCEADD Q_RES..2
(-975 725);
FORCEPROP 1 LAST LOCATION PR3918
J 0
(-920 875);
DISPLAY 0.723404 (-920 875);
PAINT AQUA (-920 875);
FORCEPROP 0 LAST $SEC 1
J 0
(-900 925);
DISPLAY 0.680851 (-900 925);
PAINT MONO (-900 925);
DISPLAY INVISIBLE (-900 925);
FORCEPROP 0 LAST CDS_SEC 1
J 0
(-900 925);
DISPLAY 1.021277 (-900 925);
DISPLAY INVISIBLE (-900 925);
FORCEPROP 1 LASTPIN (-975 825) $PN 1
J 0
(-970 787);
DISPLAY 0.787234 (-970 787);
PAINT MONO (-970 787);
FORCEPROP 1 LASTPIN (-975 625) $PN 2
J 0
(-970 635);
DISPLAY 0.787234 (-970 635);
PAINT MONO (-970 635);
FORCEPROP 1 LAST MATERIAL CHIP
J 0
(-925 675);
DISPLAY 0.723404 (-925 675);
PAINT SKYBLUE (-925 675);
FORCEPROP 1 LAST WATTAGE 1/16W
J 0
(-925 725);
DISPLAY 0.723404 (-925 725);
PAINT SKYBLUE (-925 725);
FORCEPROP 1 LAST PART_NUMBER CS22002BB07
J 0
(-925 625);
DISPLAY 0.723404 (-925 625);
PAINT WHITE (-925 625);
FORCEPROP 1 LAST PACK_TYPE 0402LF
J 0
(-925 575);
DISPLAY 0.723404 (-925 575);
PAINT SKYBLUE (-925 575);
FORCEPROP 1 LAST TOLERANCE 0.1%
J 0
(-920 775);
DISPLAY 0.723404 (-920 775);
PAINT SKYBLUE (-920 775);
FORCEPROP 1 LAST VALUE 2K
J 0
(-920 825);
DISPLAY 0.723404 (-920 825);
PAINT SKYBLUE (-920 825);
FORCEPROP 2 LAST CDS_LIB pure_quanta
J 0
(-975 725);
DISPLAY INVISIBLE (-975 725);
FORCEPROP 1 LAST PATH I34
J 0
(-925 900);
DISPLAY 0.978723 (-925 900);
PAINT WHITE (-925 900);
DISPLAY INVISIBLE (-925 900);
FORCEADD MP5991GLUZ..1
(0 1475);
FORCEPROP 1 LAST LOCATION PU287
J 0
(-320 2556);
DISPLAY 0.723404 (-320 2556);
PAINT GREEN (-320 2556);
FORCEPROP 2 LAST SEC 1
J 0
(-300 2700);
DISPLAY 0.680851 (-300 2700);
PAINT MONO (-300 2700);
DISPLAY INVISIBLE (-300 2700);
FORCEPROP 2 LASTPIN (-475 1050) $PN 23
J 2
(-485 1060);
DISPLAY 0.680851 (-485 1060);
PAINT MONO (-485 1060);
FORCEPROP 2 LASTPIN (475 1400) $PN 3
J 0
(485 1410);
DISPLAY 0.680851 (485 1410);
PAINT MONO (485 1410);
FORCEPROP 2 LASTPIN (475 1300) $PN 6
J 0
(485 1310);
DISPLAY 0.680851 (485 1310);
PAINT MONO (485 1310);
FORCEPROP 2 LASTPIN (-475 750) $PN 20
J 2
(-485 760);
DISPLAY 0.680851 (-485 760);
PAINT MONO (-485 760);
FORCEPROP 2 LASTPIN (475 1100) $PN 5
J 0
(485 1110);
DISPLAY 0.680851 (485 1110);
PAINT MONO (485 1110);
FORCEPROP 2 LASTPIN (-475 950) $PN 22
J 2
(-485 960);
DISPLAY 0.680851 (-485 960);
PAINT MONO (-485 960);
FORCEPROP 2 LASTPIN (-475 1550) $PN 8
J 2
(-485 1560);
DISPLAY 0.680851 (-485 1560);
PAINT MONO (-485 1560);
FORCEPROP 2 LASTPIN (475 1200) $PN 7
J 0
(485 1210);
DISPLAY 0.680851 (485 1210);
PAINT MONO (485 1210);
FORCEPROP 2 LASTPIN (-475 1150) $PN 24
J 2
(-485 1160);
DISPLAY 0.680851 (-485 1160);
PAINT MONO (-485 1160);
FORCEPROP 2 LASTPIN (-475 1250) $PN 4
J 2
(-485 1260);
DISPLAY 0.680851 (-485 1260);
PAINT MONO (-485 1260);
FORCEPROP 2 LASTPIN (-475 1450) $PN 17
J 2
(-485 1460);
DISPLAY 0.680851 (-485 1460);
PAINT MONO (-485 1460);
FORCEPROP 2 LASTPIN (475 900) $PN 19
J 0
(485 910);
DISPLAY 0.680851 (485 910);
PAINT MONO (485 910);
FORCEPROP 2 LASTPIN (-475 1650) $PN 21
J 2
(-485 1660);
DISPLAY 0.680851 (-485 1660);
PAINT MONO (-485 1660);
FORCEPROP 2 LASTPIN (-475 2200) $PN 9
J 2
(-485 2210);
DISPLAY 0.680851 (-485 2210);
PAINT MONO (-485 2210);
FORCEPROP 2 LASTPIN (-475 2150) $PN 10
J 2
(-485 2160);
DISPLAY 0.680851 (-485 2160);
PAINT MONO (-485 2160);
FORCEPROP 2 LASTPIN (-475 2100) $PN 11
J 2
(-485 2110);
DISPLAY 0.680851 (-485 2110);
PAINT MONO (-485 2110);
FORCEPROP 2 LASTPIN (-475 2050) $PN 12
J 2
(-485 2060);
DISPLAY 0.680851 (-485 2060);
PAINT MONO (-485 2060);
FORCEPROP 2 LASTPIN (-475 2000) $PN 13
J 2
(-485 2010);
DISPLAY 0.680851 (-485 2010);
PAINT MONO (-485 2010);
FORCEPROP 2 LASTPIN (-475 1950) $PN 14
J 2
(-485 1960);
DISPLAY 0.680851 (-485 1960);
PAINT MONO (-485 1960);
FORCEPROP 2 LASTPIN (-475 1900) $PN 15
J 2
(-485 1910);
DISPLAY 0.680851 (-485 1910);
PAINT MONO (-485 1910);
FORCEPROP 2 LASTPIN (-475 1850) $PN 16
J 2
(-485 1860);
DISPLAY 0.680851 (-485 1860);
PAINT MONO (-485 1860);
FORCEPROP 2 LASTPIN (-475 1800) $PN 33
J 2
(-485 1810);
DISPLAY 0.680851 (-485 1810);
PAINT MONO (-485 1810);
FORCEPROP 2 LASTPIN (475 2200) $PN 1
J 0
(485 2210);
DISPLAY 0.680851 (485 2210);
PAINT MONO (485 2210);
FORCEPROP 2 LASTPIN (475 2150) $PN 2
J 0
(485 2160);
DISPLAY 0.680851 (485 2160);
PAINT MONO (485 2160);
FORCEPROP 2 LASTPIN (475 2100) $PN 25
J 0
(485 2110);
DISPLAY 0.680851 (485 2110);
PAINT MONO (485 2110);
FORCEPROP 2 LASTPIN (475 2050) $PN 26
J 0
(485 2060);
DISPLAY 0.680851 (485 2060);
PAINT MONO (485 2060);
FORCEPROP 2 LASTPIN (475 2000) $PN 27
J 0
(485 2010);
DISPLAY 0.680851 (485 2010);
PAINT MONO (485 2010);
FORCEPROP 2 LASTPIN (475 1950) $PN 28
J 0
(485 1960);
DISPLAY 0.680851 (485 1960);
PAINT MONO (485 1960);
FORCEPROP 2 LASTPIN (475 1900) $PN 29
J 0
(485 1910);
DISPLAY 0.680851 (485 1910);
PAINT MONO (485 1910);
FORCEPROP 2 LASTPIN (475 1850) $PN 30
J 0
(485 1860);
DISPLAY 0.680851 (485 1860);
PAINT MONO (485 1860);
FORCEPROP 2 LASTPIN (475 1800) $PN 31
J 0
(485 1810);
DISPLAY 0.680851 (485 1810);
PAINT MONO (485 1810);
FORCEPROP 2 LASTPIN (475 1750) $PN 32
J 0
(485 1760);
DISPLAY 0.680851 (485 1760);
PAINT MONO (485 1760);
FORCEPROP 2 LASTPIN (475 1000) $PN 18
J 0
(485 1010);
DISPLAY 0.680851 (485 1010);
PAINT MONO (485 1010);
FORCEPROP 1 LAST MATERIAL IC
J 0
(-320 2282);
DISPLAY 0.723404 (-320 2282);
PAINT GREEN (-320 2282);
FORCEPROP 1 LAST PART_NUMBER AL005991A00
J 0
(-320 2409);
DISPLAY 0.723404 (-320 2409);
PAINT GREEN (-320 2409);
FORCEPROP 2 LAST VALUE MP5991GLU-Z
J 0
(-300 2600);
DISPLAY 1.021277 (-300 2600);
FORCEPROP 2 LAST PART_TYPE SMLF
J 0
(-300 2650);
DISPLAY 1.021277 (-300 2650);
FORCEPROP 2 LAST CDS_LIB pure_quanta
J 0
(0 1475);
DISPLAY INVISIBLE (0 1475);
FORCEPROP 1 LAST CDS_LMAN_SYM_OUTLINE -325,775,325,-775
J 0
(0 1475);
DISPLAY 0.468085 (0 1475);
PAINT GREEN (0 1475);
DISPLAY INVISIBLE (0 1475);
FORCEPROP 1 LAST NEEDS_NO_SIZE TRUE
J 0
(0 1475);
DISPLAY 0.723404 (0 1475);
PAINT GREEN (0 1475);
DISPLAY INVISIBLE (0 1475);
FORCEPROP 2 LAST SEC_TYPE 
J 0
(-300 2700);
DISPLAY 1.021277 (-300 2700);
DISPLAY INVISIBLE (-300 2700);
FORCEPROP 1 LAST PATH I35
J 0
(0 1475);
DISPLAY 0.723404 (0 1475);
PAINT GREEN (0 1475);
DISPLAY INVISIBLE (0 1475);
FORCEADD UNIVERSAL_POWER..1
(-975 2350);
FORCEPROP 3 LASTPIN (-975 2300) SIG_NAME P12V_PSU\g
J 0
(-965 2310);
DISPLAY 0.659574 (-965 2310);
PAINT MONO (-965 2310);
DISPLAY INVISIBLE (-965 2310);
FORCEPROP 1 LAST HDL_POWER P12V_PSU
J 1
(-975 2400);
DISPLAY 0.723404 (-975 2400);
PAINT GREEN (-975 2400);
FORCEPROP 2 LAST ROOM AUX_SW
J 0
(-975 2450);
DISPLAY 0.617021 (-975 2450);
FORCEPROP 2 LAST CDS_LIB pure_quanta_power
J 0
(-975 2350);
DISPLAY INVISIBLE (-975 2350);
FORCEPROP 2 LAST BOM_COST MIO_VRD_SB
J 0
(-975 2450);
DISPLAY 0.617021 (-975 2450);
PAINT PURPLE (-975 2450);
DISPLAY INVISIBLE (-975 2450);
FORCEPROP 1 LAST PATH I36
J 0
(-925 2375);
DISPLAY 0.872340 (-925 2375);
PAINT AQUA (-925 2375);
DISPLAY INVISIBLE (-925 2375);
FORCEADD UNIVERSAL_GND..1
(975 -2275);
FORCEPROP 3 LASTPIN (975 -2225) SIG_NAME AGND_HSC\g
J 0
(985 -2215);
DISPLAY 0.659574 (985 -2215);
PAINT MONO (985 -2215);
DISPLAY INVISIBLE (985 -2215);
FORCEPROP 1 LAST HDL_POWER AGND_HSC
J 1
(1000 -2350);
DISPLAY 0.723404 (1000 -2350);
PAINT GREEN (1000 -2350);
FORCEPROP 2 LAST CDS_LIB pure_quanta_power
J 0
(975 -2275);
DISPLAY INVISIBLE (975 -2275);
FORCEPROP 1 LAST PATH I37
J 0
(1050 -2275);
DISPLAY 0.872340 (1050 -2275);
PAINT AQUA (1050 -2275);
DISPLAY INVISIBLE (1050 -2275);
FORCEADD Q_CAP..1
(975 -2050);
FORCEPROP 1 LAST LOCATION PC2185
J 0
(1025 -1975);
DISPLAY 0.723404 (1025 -1975);
PAINT AQUA (1025 -1975);
FORCEPROP 0 LAST $SEC 1
J 0
(1025 -1925);
DISPLAY 0.680851 (1025 -1925);
PAINT MONO (1025 -1925);
DISPLAY INVISIBLE (1025 -1925);
FORCEPROP 0 LAST CDS_SEC 1
J 0
(1025 -1925);
DISPLAY 1.021277 (1025 -1925);
DISPLAY INVISIBLE (1025 -1925);
FORCEPROP 1 LASTPIN (975 -1950) $PN 1
J 0
(985 -1970);
DISPLAY 0.787234 (985 -1970);
PAINT MONO (985 -1970);
FORCEPROP 1 LASTPIN (975 -2150) $PN 2
J 0
(985 -2170);
DISPLAY 0.787234 (985 -2170);
PAINT MONO (985 -2170);
FORCEPROP 1 LAST VALUE 0.068UF
J 0
(1025 -2025);
DISPLAY 0.723404 (1025 -2025);
PAINT SKYBLUE (1025 -2025);
FORCEPROP 1 LAST VOLTAGE 16V
J 0
(1025 -2075);
DISPLAY 0.723404 (1025 -2075);
PAINT SKYBLUE (1025 -2075);
FORCEPROP 1 LAST MATERIAL X7R
J 0
(1025 -2125);
DISPLAY 0.723404 (1025 -2125);
PAINT SKYBLUE (1025 -2125);
FORCEPROP 1 LAST PART_NUMBER CH3683K1B09
J 0
(1025 -2175);
DISPLAY 0.723404 (1025 -2175);
PAINT WHITE (1025 -2175);
FORCEPROP 1 LAST PACK_TYPE 0402
J 0
(1025 -2225);
DISPLAY 0.723404 (1025 -2225);
PAINT SKYBLUE (1025 -2225);
FORCEPROP 2 LAST CDS_LIB pure_quanta
J 0
(975 -2050);
DISPLAY INVISIBLE (975 -2050);
FORCEPROP 1 LAST TOLERANCE 10%
J 0
(1025 -2100);
DISPLAY 0.978723 (1025 -2100);
PAINT SKYBLUE (1025 -2100);
DISPLAY INVISIBLE (1025 -2100);
FORCEPROP 1 LAST PATH I38
J 0
(1025 -1900);
DISPLAY 0.978723 (1025 -1900);
PAINT WHITE (1025 -1900);
DISPLAY INVISIBLE (1025 -1900);
FORCEADD Q_RES..1
(1475 -1500);
FORCEPROP 1 LAST LOCATION PR3922
J 0
(1175 -1500);
DISPLAY 0.723404 (1175 -1500);
PAINT AQUA (1175 -1500);
FORCEPROP 0 LAST $SEC 1
J 0
(1625 -1425);
DISPLAY 0.680851 (1625 -1425);
PAINT MONO (1625 -1425);
DISPLAY INVISIBLE (1625 -1425);
FORCEPROP 0 LAST CDS_SEC 1
J 0
(1625 -1425);
DISPLAY 1.021277 (1625 -1425);
DISPLAY INVISIBLE (1625 -1425);
FORCEPROP 1 LASTPIN (1375 -1500) $PN 1
J 0
(1387 -1488);
DISPLAY 0.787234 (1387 -1488);
PAINT MONO (1387 -1488);
FORCEPROP 1 LASTPIN (1575 -1500) $PN 2
J 0
(1537 -1488);
DISPLAY 0.787234 (1537 -1488);
PAINT MONO (1537 -1488);
FORCEPROP 1 LAST PART_NUMBER CS00002JB13
J 0
(1150 -1550);
DISPLAY 0.723404 (1150 -1550);
PAINT WHITE (1150 -1550);
FORCEPROP 1 LAST VALUE 0
J 2
(1625 -1475);
DISPLAY 0.723404 (1625 -1475);
PAINT SKYBLUE (1625 -1475);
FORCEPROP 1 LAST TOLERANCE 5%
J 0
(1600 -1550);
DISPLAY 0.723404 (1600 -1550);
PAINT SKYBLUE (1600 -1550);
FORCEPROP 1 LAST MATERIAL CHIP
J 0
(1650 -1600);
DISPLAY 0.723404 (1650 -1600);
PAINT SKYBLUE (1650 -1600);
FORCEPROP 1 LAST WATTAGE 1/16W
J 2
(1350 -1600);
DISPLAY 0.723404 (1350 -1600);
PAINT SKYBLUE (1350 -1600);
FORCEPROP 1 LAST PACK_TYPE 0402LF
J 0
(1400 -1600);
DISPLAY 0.723404 (1400 -1600);
PAINT SKYBLUE (1400 -1600);
FORCEPROP 2 LAST CDS_LIB pure_quanta
J 0
(1475 -1500);
DISPLAY INVISIBLE (1475 -1500);
FORCEPROP 1 LAST PATH I39
J 0
(1425 -1350);
DISPLAY 0.978723 (1425 -1350);
PAINT WHITE (1425 -1350);
DISPLAY INVISIBLE (1425 -1350);
FORCEADD Q_CAP..1
(-3475 -1425);
FORCEPROP 1 LAST LOCATION PC2181
J 0
(-3400 -1275);
DISPLAY 0.723404 (-3400 -1275);
PAINT AQUA (-3400 -1275);
FORCEPROP 0 LAST $SEC 1
J 0
(-3400 -1225);
DISPLAY 0.680851 (-3400 -1225);
PAINT MONO (-3400 -1225);
DISPLAY INVISIBLE (-3400 -1225);
FORCEPROP 0 LAST CDS_SEC 1
J 0
(-3400 -1225);
DISPLAY 1.021277 (-3400 -1225);
DISPLAY INVISIBLE (-3400 -1225);
FORCEPROP 1 LASTPIN (-3475 -1325) $PN 1
J 0
(-3465 -1345);
DISPLAY 0.787234 (-3465 -1345);
PAINT MONO (-3465 -1345);
FORCEPROP 1 LASTPIN (-3475 -1525) $PN 2
J 0
(-3465 -1545);
DISPLAY 0.787234 (-3465 -1545);
PAINT MONO (-3465 -1545);
FORCEPROP 1 LAST VALUE 1UF
J 0
(-3400 -1325);
DISPLAY 0.723404 (-3400 -1325);
PAINT SKYBLUE (-3400 -1325);
FORCEPROP 1 LAST PART_NUMBER CH5104KEB02
J 0
(-3400 -1475);
DISPLAY 0.723404 (-3400 -1475);
PAINT WHITE (-3400 -1475);
FORCEPROP 1 LAST PACK_TYPE C0402
J 0
(-3400 -1525);
DISPLAY 0.723404 (-3400 -1525);
PAINT SKYBLUE (-3400 -1525);
FORCEPROP 1 LAST MATERIAL X6S
J 0
(-3400 -1425);
DISPLAY 0.723404 (-3400 -1425);
PAINT SKYBLUE (-3400 -1425);
FORCEPROP 1 LAST VOLTAGE 25V
J 0
(-3400 -1375);
DISPLAY 0.723404 (-3400 -1375);
PAINT SKYBLUE (-3400 -1375);
FORCEPROP 2 LAST CDS_LIB pure_quanta
J 0
(-3475 -1425);
DISPLAY INVISIBLE (-3475 -1425);
FORCEPROP 1 LAST TOLERANCE 10%
J 0
(-3425 -1475);
DISPLAY 0.978723 (-3425 -1475);
PAINT SKYBLUE (-3425 -1475);
DISPLAY INVISIBLE (-3425 -1475);
FORCEPROP 1 LAST PATH I4
J 0
(-3425 -1275);
DISPLAY 0.978723 (-3425 -1275);
PAINT WHITE (-3425 -1275);
DISPLAY INVISIBLE (-3425 -1275);
FORCEADD Q_RES..1
(1475 -1325);
FORCEPROP 1 LAST LOCATION PR3921
J 0
(1175 -1325);
DISPLAY 0.723404 (1175 -1325);
PAINT AQUA (1175 -1325);
FORCEPROP 0 LAST $SEC 1
J 0
(1625 -1250);
DISPLAY 0.680851 (1625 -1250);
PAINT MONO (1625 -1250);
DISPLAY INVISIBLE (1625 -1250);
FORCEPROP 0 LAST CDS_SEC 1
J 0
(1625 -1250);
DISPLAY 1.021277 (1625 -1250);
DISPLAY INVISIBLE (1625 -1250);
FORCEPROP 1 LASTPIN (1375 -1325) $PN 1
J 0
(1387 -1313);
DISPLAY 0.787234 (1387 -1313);
PAINT MONO (1387 -1313);
FORCEPROP 1 LASTPIN (1575 -1325) $PN 2
J 0
(1537 -1313);
DISPLAY 0.787234 (1537 -1313);
PAINT MONO (1537 -1313);
FORCEPROP 1 LAST TOLERANCE 5%
J 0
(1600 -1375);
DISPLAY 0.723404 (1600 -1375);
PAINT SKYBLUE (1600 -1375);
FORCEPROP 1 LAST PACK_TYPE 0402LF
J 0
(1400 -1425);
DISPLAY 0.723404 (1400 -1425);
PAINT SKYBLUE (1400 -1425);
FORCEPROP 1 LAST VALUE 0
J 2
(1625 -1300);
DISPLAY 0.723404 (1625 -1300);
PAINT SKYBLUE (1625 -1300);
FORCEPROP 1 LAST PART_NUMBER CS00002JB13
J 0
(1150 -1375);
DISPLAY 0.723404 (1150 -1375);
PAINT WHITE (1150 -1375);
FORCEPROP 1 LAST WATTAGE 1/16W
J 2
(1350 -1425);
DISPLAY 0.723404 (1350 -1425);
PAINT SKYBLUE (1350 -1425);
FORCEPROP 1 LAST MATERIAL CHIP
J 0
(1650 -1425);
DISPLAY 0.723404 (1650 -1425);
PAINT SKYBLUE (1650 -1425);
FORCEPROP 2 LAST CDS_LIB pure_quanta
J 0
(1475 -1325);
DISPLAY INVISIBLE (1475 -1325);
FORCEPROP 1 LAST PATH I40
J 0
(1425 -1175);
DISPLAY 0.978723 (1425 -1175);
PAINT WHITE (1425 -1175);
DISPLAY INVISIBLE (1425 -1175);
FORCEADD UNIVERSAL_POWER..1
(1100 -450);
FORCEPROP 3 LASTPIN (1100 -500) SIG_NAME P12V_AUX\g
J 0
(1110 -490);
DISPLAY 0.659574 (1110 -490);
PAINT MONO (1110 -490);
DISPLAY INVISIBLE (1110 -490);
FORCEPROP 1 LAST HDL_POWER P12V_AUX
J 1
(1100 -400);
DISPLAY 0.723404 (1100 -400);
PAINT GREEN (1100 -400);
FORCEPROP 2 LAST ROOM AUX_SW
J 0
(1100 -350);
DISPLAY 0.617021 (1100 -350);
FORCEPROP 2 LAST BOM_COST MIO_VRD_SB
J 0
(1100 -350);
DISPLAY 0.617021 (1100 -350);
PAINT PURPLE (1100 -350);
DISPLAY INVISIBLE (1100 -350);
FORCEPROP 2 LAST CDS_LIB pure_quanta_power
J 0
(1100 -450);
DISPLAY INVISIBLE (1100 -450);
FORCEPROP 1 LAST PATH I41
J 0
(1150 -425);
DISPLAY 0.872340 (1150 -425);
PAINT AQUA (1150 -425);
DISPLAY INVISIBLE (1150 -425);
FORCEADD OFFPAGE..4
(2250 -1900);
FORCEPROP 2 LAST $XR2 303 
J 0
(2676 -1900);
DISPLAY 0.638298 (2676 -1900);
PAINT MONO (2676 -1900);
FORCEPROP 2 LAST $XR1 302 
J 0
(2556 -1900);
DISPLAY 0.638298 (2556 -1900);
PAINT MONO (2556 -1900);
FORCEPROP 2 LAST $XR0 301 
J 0
(2436 -1900);
DISPLAY 0.638298 (2436 -1900);
PAINT MONO (2436 -1900);
FORCEPROP 2 LAST CDS_LIB standard
J 0
(2250 -1900);
DISPLAY INVISIBLE (2250 -1900);
FORCEPROP 1 LAST OFFPAGE TRUE
J 0
(2575 -2025);
DISPLAY 0.872340 (2575 -2025);
PAINT GREEN (2575 -2025);
DISPLAY INVISIBLE (2575 -2025);
FORCEPROP 1 LAST COMMENT_BODY TRUE
J 0
(2225 -2000);
DISPLAY 0.872340 (2225 -2000);
PAINT GREEN (2225 -2000);
DISPLAY INVISIBLE (2225 -2000);
FORCEPROP 2 LAST PATH I42
J 0
(2700 -1850);
DISPLAY 1.021277 (2700 -1850);
DISPLAY INVISIBLE (2700 -1850);
FORCEADD OFFPAGE..5
R 2
(2250 -1800);
FORCEPROP 2 LAST $XR2 301 
J 0
(2679 -1800);
DISPLAY 0.638298 (2679 -1800);
PAINT MONO (2679 -1800);
FORCEPROP 2 LAST $XR1 303 
J 0
(2559 -1800);
DISPLAY 0.638298 (2559 -1800);
PAINT MONO (2559 -1800);
FORCEPROP 2 LAST $XR0 302 
J 0
(2439 -1800);
DISPLAY 0.638298 (2439 -1800);
PAINT MONO (2439 -1800);
FORCEPROP 2 LAST CDS_LIB standard
J 2
(2250 -1800);
DISPLAY INVISIBLE (2250 -1800);
FORCEPROP 1 LAST OFFPAGE TRUE
J 2
(1925 -1925);
DISPLAY 0.872340 (1925 -1925);
PAINT AQUA (1925 -1925);
DISPLAY INVISIBLE (1925 -1925);
FORCEPROP 1 LAST COMMENT_BODY TRUE
J 2
(2150 -1875);
DISPLAY 1.170213 (2150 -1875);
PAINT GREEN (2150 -1875);
DISPLAY INVISIBLE (2150 -1875);
FORCEPROP 2 LAST PATH I43
J 0
(2700 -1750);
DISPLAY 1.021277 (2700 -1750);
DISPLAY INVISIBLE (2700 -1750);
FORCEADD OFFPAGE..5
R 2
(2250 -1700);
FORCEPROP 2 LAST $XR2 301 
J 0
(2679 -1700);
DISPLAY 0.638298 (2679 -1700);
PAINT MONO (2679 -1700);
FORCEPROP 2 LAST $XR1 303 
J 0
(2559 -1700);
DISPLAY 0.638298 (2559 -1700);
PAINT MONO (2559 -1700);
FORCEPROP 2 LAST $XR0 302 
J 0
(2439 -1700);
DISPLAY 0.638298 (2439 -1700);
PAINT MONO (2439 -1700);
FORCEPROP 2 LAST CDS_LIB standard
J 2
(2250 -1700);
DISPLAY INVISIBLE (2250 -1700);
FORCEPROP 1 LAST OFFPAGE TRUE
J 2
(1925 -1825);
DISPLAY 0.872340 (1925 -1825);
PAINT AQUA (1925 -1825);
DISPLAY INVISIBLE (1925 -1825);
FORCEPROP 1 LAST COMMENT_BODY TRUE
J 2
(2150 -1775);
DISPLAY 1.170213 (2150 -1775);
PAINT GREEN (2150 -1775);
DISPLAY INVISIBLE (2150 -1775);
FORCEPROP 2 LAST PATH I44
J 0
(2700 -1650);
DISPLAY 1.021277 (2700 -1650);
DISPLAY INVISIBLE (2700 -1650);
FORCEADD OFFPAGE..4
(2250 -1500);
FORCEPROP 2 LAST $XR2 303 
J 0
(2676 -1500);
DISPLAY 0.638298 (2676 -1500);
PAINT MONO (2676 -1500);
FORCEPROP 2 LAST $XR1 302 
J 0
(2556 -1500);
DISPLAY 0.638298 (2556 -1500);
PAINT MONO (2556 -1500);
FORCEPROP 2 LAST $XR0 301 
J 0
(2436 -1500);
DISPLAY 0.638298 (2436 -1500);
PAINT MONO (2436 -1500);
FORCEPROP 2 LAST CDS_LIB standard
J 0
(2250 -1500);
DISPLAY INVISIBLE (2250 -1500);
FORCEPROP 1 LAST OFFPAGE TRUE
J 0
(2575 -1625);
DISPLAY 0.872340 (2575 -1625);
PAINT GREEN (2575 -1625);
DISPLAY INVISIBLE (2575 -1625);
FORCEPROP 1 LAST COMMENT_BODY TRUE
J 0
(2225 -1600);
DISPLAY 0.872340 (2225 -1600);
PAINT GREEN (2225 -1600);
DISPLAY INVISIBLE (2225 -1600);
FORCEPROP 2 LAST PATH I45
J 0
(2700 -1450);
DISPLAY 1.021277 (2700 -1450);
DISPLAY INVISIBLE (2700 -1450);
FORCEADD OFFPAGE..5
R 2
(2250 -1325);
FORCEPROP 2 LAST $XR2 301 
J 0
(2679 -1325);
DISPLAY 0.638298 (2679 -1325);
PAINT MONO (2679 -1325);
FORCEPROP 2 LAST $XR1 303 
J 0
(2559 -1325);
DISPLAY 0.638298 (2559 -1325);
PAINT MONO (2559 -1325);
FORCEPROP 2 LAST $XR0 302 
J 0
(2439 -1325);
DISPLAY 0.638298 (2439 -1325);
PAINT MONO (2439 -1325);
FORCEPROP 2 LAST CDS_LIB standard
J 0
(2250 -1325);
DISPLAY INVISIBLE (2250 -1325);
FORCEPROP 1 LAST OFFPAGE TRUE
J 2
(1925 -1450);
DISPLAY 0.872340 (1925 -1450);
PAINT AQUA (1925 -1450);
DISPLAY INVISIBLE (1925 -1450);
FORCEPROP 1 LAST COMMENT_BODY TRUE
J 2
(2150 -1400);
DISPLAY 1.170213 (2150 -1400);
PAINT GREEN (2150 -1400);
DISPLAY INVISIBLE (2150 -1400);
FORCEPROP 2 LAST PATH I46
J 0
(2700 -1275);
DISPLAY 1.021277 (2700 -1275);
DISPLAY INVISIBLE (2700 -1275);
FORCEADD Q_CAP..1
(975 750);
FORCEPROP 1 LAST LOCATION PC2184
J 0
(1025 825);
DISPLAY 0.723404 (1025 825);
PAINT AQUA (1025 825);
FORCEPROP 0 LAST $SEC 1
J 0
(1025 875);
DISPLAY 0.680851 (1025 875);
PAINT MONO (1025 875);
DISPLAY INVISIBLE (1025 875);
FORCEPROP 0 LAST CDS_SEC 1
J 0
(1025 875);
DISPLAY 1.021277 (1025 875);
DISPLAY INVISIBLE (1025 875);
FORCEPROP 1 LASTPIN (975 850) $PN 1
J 0
(985 830);
DISPLAY 0.787234 (985 830);
PAINT MONO (985 830);
FORCEPROP 1 LASTPIN (975 650) $PN 2
J 0
(985 630);
DISPLAY 0.787234 (985 630);
PAINT MONO (985 630);
FORCEPROP 1 LAST VALUE 0.068UF
J 0
(1025 775);
DISPLAY 0.723404 (1025 775);
PAINT SKYBLUE (1025 775);
FORCEPROP 1 LAST MATERIAL X7R
J 0
(1025 675);
DISPLAY 0.723404 (1025 675);
PAINT SKYBLUE (1025 675);
FORCEPROP 1 LAST PACK_TYPE 0402
J 0
(1025 575);
DISPLAY 0.723404 (1025 575);
PAINT SKYBLUE (1025 575);
FORCEPROP 1 LAST VOLTAGE 16V
J 0
(1025 725);
DISPLAY 0.723404 (1025 725);
PAINT SKYBLUE (1025 725);
FORCEPROP 1 LAST PART_NUMBER CH3683K1B09
J 0
(1025 625);
DISPLAY 0.723404 (1025 625);
PAINT WHITE (1025 625);
FORCEPROP 2 LAST CDS_LIB pure_quanta
J 0
(975 750);
DISPLAY INVISIBLE (975 750);
FORCEPROP 1 LAST TOLERANCE 10%
J 0
(1025 700);
DISPLAY 0.978723 (1025 700);
PAINT SKYBLUE (1025 700);
DISPLAY INVISIBLE (1025 700);
FORCEPROP 1 LAST PATH I47
J 0
(1025 900);
DISPLAY 0.978723 (1025 900);
PAINT WHITE (1025 900);
DISPLAY INVISIBLE (1025 900);
FORCEADD UNIVERSAL_GND..1
(975 525);
FORCEPROP 3 LASTPIN (975 575) SIG_NAME AGND_HSC\g
J 0
(985 585);
DISPLAY 0.659574 (985 585);
PAINT MONO (985 585);
DISPLAY INVISIBLE (985 585);
FORCEPROP 1 LAST HDL_POWER AGND_HSC
J 1
(1000 450);
DISPLAY 0.723404 (1000 450);
PAINT GREEN (1000 450);
FORCEPROP 2 LAST CDS_LIB pure_quanta_power
J 0
(975 525);
DISPLAY INVISIBLE (975 525);
FORCEPROP 1 LAST PATH I48
J 0
(1050 525);
DISPLAY 0.872340 (1050 525);
PAINT AQUA (1050 525);
DISPLAY INVISIBLE (1050 525);
FORCEADD Q_RES..1
(1475 1300);
FORCEPROP 1 LAST LOCATION PR3920
J 0
(1175 1300);
DISPLAY 0.723404 (1175 1300);
PAINT AQUA (1175 1300);
FORCEPROP 0 LAST $SEC 1
J 0
(1625 1375);
DISPLAY 0.680851 (1625 1375);
PAINT MONO (1625 1375);
DISPLAY INVISIBLE (1625 1375);
FORCEPROP 0 LAST CDS_SEC 1
J 0
(1625 1375);
DISPLAY 1.021277 (1625 1375);
DISPLAY INVISIBLE (1625 1375);
FORCEPROP 1 LASTPIN (1375 1300) $PN 1
J 0
(1387 1312);
DISPLAY 0.787234 (1387 1312);
PAINT MONO (1387 1312);
FORCEPROP 1 LASTPIN (1575 1300) $PN 2
J 0
(1537 1312);
DISPLAY 0.787234 (1537 1312);
PAINT MONO (1537 1312);
FORCEPROP 1 LAST PART_NUMBER CS00002JB13
J 0
(1150 1250);
DISPLAY 0.723404 (1150 1250);
PAINT WHITE (1150 1250);
FORCEPROP 1 LAST PACK_TYPE 0402LF
J 0
(1400 1200);
DISPLAY 0.723404 (1400 1200);
PAINT SKYBLUE (1400 1200);
FORCEPROP 1 LAST MATERIAL CHIP
J 0
(1650 1200);
DISPLAY 0.723404 (1650 1200);
PAINT SKYBLUE (1650 1200);
FORCEPROP 1 LAST TOLERANCE 5%
J 0
(1600 1250);
DISPLAY 0.723404 (1600 1250);
PAINT SKYBLUE (1600 1250);
FORCEPROP 1 LAST VALUE 0
J 2
(1625 1325);
DISPLAY 0.723404 (1625 1325);
PAINT SKYBLUE (1625 1325);
FORCEPROP 1 LAST WATTAGE 1/16W
J 2
(1350 1200);
DISPLAY 0.723404 (1350 1200);
PAINT SKYBLUE (1350 1200);
FORCEPROP 2 LAST CDS_LIB pure_quanta
J 0
(1475 1300);
DISPLAY INVISIBLE (1475 1300);
FORCEPROP 1 LAST PATH I49
J 0
(1425 1450);
DISPLAY 0.978723 (1425 1450);
PAINT WHITE (1425 1450);
DISPLAY INVISIBLE (1425 1450);
FORCEADD Q_RES..1
R 1
(-3475 -950);
FORCEPROP 1 LAST LOCATION PR3911
J 0
(-3400 -800);
DISPLAY 0.723404 (-3400 -800);
PAINT AQUA (-3400 -800);
FORCEPROP 0 LAST $SEC 1
R 1
J 0
(-3400 -750);
DISPLAY 0.680851 (-3400 -750);
PAINT MONO (-3400 -750);
DISPLAY INVISIBLE (-3400 -750);
FORCEPROP 0 LAST CDS_SEC 1
R 1
J 0
(-3400 -750);
DISPLAY 1.021277 (-3400 -750);
DISPLAY INVISIBLE (-3400 -750);
FORCEPROP 1 LASTPIN (-3475 -1050) $PN 1
R 1
J 0
(-3487 -1038);
DISPLAY 0.787234 (-3487 -1038);
PAINT MONO (-3487 -1038);
FORCEPROP 1 LASTPIN (-3475 -850) $PN 2
R 1
J 0
(-3487 -888);
DISPLAY 0.787234 (-3487 -888);
PAINT MONO (-3487 -888);
FORCEPROP 1 LAST TOLERANCE 5%
J 0
(-3400 -900);
DISPLAY 0.723404 (-3400 -900);
PAINT SKYBLUE (-3400 -900);
FORCEPROP 1 LAST MATERIAL CHIP
J 0
(-3400 -950);
DISPLAY 0.787234 (-3400 -950);
PAINT SKYBLUE (-3400 -950);
FORCEPROP 1 LAST WATTAGE 1/16W
J 0
(-3400 -1000);
DISPLAY 0.723404 (-3400 -1000);
PAINT SKYBLUE (-3400 -1000);
FORCEPROP 1 LAST PACK_TYPE 0402LF
J 0
(-3400 -1100);
DISPLAY 0.723404 (-3400 -1100);
PAINT SKYBLUE (-3400 -1100);
FORCEPROP 1 LAST PART_NUMBER CS00002JB13
J 0
(-3400 -1050);
DISPLAY 0.723404 (-3400 -1050);
PAINT WHITE (-3400 -1050);
FORCEPROP 1 LAST VALUE 0
R 2
J 0
(-3375 -825);
DISPLAY 0.723404 (-3375 -825);
PAINT SKYBLUE (-3375 -825);
FORCEPROP 2 LAST CDS_LIB pure_quanta
J 0
(-3475 -950);
DISPLAY INVISIBLE (-3475 -950);
FORCEPROP 1 LAST PATH I5
R 1
J 0
(-3625 -1000);
DISPLAY 0.978723 (-3625 -1000);
PAINT WHITE (-3625 -1000);
DISPLAY INVISIBLE (-3625 -1000);
FORCEADD Q_RES..1
(1475 1475);
FORCEPROP 1 LAST LOCATION PR3919
J 0
(1175 1475);
DISPLAY 0.723404 (1175 1475);
PAINT AQUA (1175 1475);
FORCEPROP 0 LAST $SEC 1
J 0
(1625 1550);
DISPLAY 0.680851 (1625 1550);
PAINT MONO (1625 1550);
DISPLAY INVISIBLE (1625 1550);
FORCEPROP 0 LAST CDS_SEC 1
J 0
(1625 1550);
DISPLAY 1.021277 (1625 1550);
DISPLAY INVISIBLE (1625 1550);
FORCEPROP 1 LASTPIN (1375 1475) $PN 1
J 0
(1387 1487);
DISPLAY 0.787234 (1387 1487);
PAINT MONO (1387 1487);
FORCEPROP 1 LASTPIN (1575 1475) $PN 2
J 0
(1537 1487);
DISPLAY 0.787234 (1537 1487);
PAINT MONO (1537 1487);
FORCEPROP 1 LAST WATTAGE 1/16W
J 2
(1350 1375);
DISPLAY 0.723404 (1350 1375);
PAINT SKYBLUE (1350 1375);
FORCEPROP 1 LAST PART_NUMBER CS00002JB13
J 0
(1150 1425);
DISPLAY 0.723404 (1150 1425);
PAINT WHITE (1150 1425);
FORCEPROP 1 LAST PACK_TYPE 0402LF
J 0
(1400 1375);
DISPLAY 0.723404 (1400 1375);
PAINT SKYBLUE (1400 1375);
FORCEPROP 1 LAST VALUE 0
J 2
(1625 1500);
DISPLAY 0.723404 (1625 1500);
PAINT SKYBLUE (1625 1500);
FORCEPROP 1 LAST TOLERANCE 5%
J 0
(1600 1425);
DISPLAY 0.723404 (1600 1425);
PAINT SKYBLUE (1600 1425);
FORCEPROP 1 LAST MATERIAL CHIP
J 0
(1650 1375);
DISPLAY 0.723404 (1650 1375);
PAINT SKYBLUE (1650 1375);
FORCEPROP 2 LAST CDS_LIB pure_quanta
J 0
(1475 1475);
DISPLAY INVISIBLE (1475 1475);
FORCEPROP 1 LAST PATH I50
J 0
(1425 1625);
DISPLAY 0.978723 (1425 1625);
PAINT WHITE (1425 1625);
DISPLAY INVISIBLE (1425 1625);
FORCEADD UNIVERSAL_POWER..1
(1100 2350);
FORCEPROP 3 LASTPIN (1100 2300) SIG_NAME P12V_AUX\g
J 0
(1110 2310);
DISPLAY 0.659574 (1110 2310);
PAINT MONO (1110 2310);
DISPLAY INVISIBLE (1110 2310);
FORCEPROP 1 LAST HDL_POWER P12V_AUX
J 1
(1100 2400);
DISPLAY 0.723404 (1100 2400);
PAINT GREEN (1100 2400);
FORCEPROP 2 LAST ROOM AUX_SW
J 0
(1100 2450);
DISPLAY 0.617021 (1100 2450);
FORCEPROP 2 LAST CDS_LIB pure_quanta_power
J 0
(1100 2350);
DISPLAY INVISIBLE (1100 2350);
FORCEPROP 2 LAST BOM_COST MIO_VRD_SB
J 0
(1100 2450);
DISPLAY 0.617021 (1100 2450);
PAINT PURPLE (1100 2450);
DISPLAY INVISIBLE (1100 2450);
FORCEPROP 1 LAST PATH I51
J 0
(1150 2375);
DISPLAY 0.872340 (1150 2375);
PAINT AQUA (1150 2375);
DISPLAY INVISIBLE (1150 2375);
FORCEADD OFFPAGE..4
(2275 900);
FORCEPROP 2 LAST $XR2 303 
J 0
(2701 900);
DISPLAY 0.638298 (2701 900);
PAINT MONO (2701 900);
FORCEPROP 2 LAST $XR1 302 
J 0
(2581 900);
DISPLAY 0.638298 (2581 900);
PAINT MONO (2581 900);
FORCEPROP 2 LAST $XR0 301 
J 0
(2461 900);
DISPLAY 0.638298 (2461 900);
PAINT MONO (2461 900);
FORCEPROP 2 LAST CDS_LIB standard
J 0
(2275 900);
DISPLAY INVISIBLE (2275 900);
FORCEPROP 1 LAST OFFPAGE TRUE
J 0
(2600 775);
DISPLAY 0.872340 (2600 775);
PAINT GREEN (2600 775);
DISPLAY INVISIBLE (2600 775);
FORCEPROP 1 LAST COMMENT_BODY TRUE
J 0
(2250 800);
DISPLAY 0.872340 (2250 800);
PAINT GREEN (2250 800);
DISPLAY INVISIBLE (2250 800);
FORCEPROP 2 LAST PATH I52
J 0
(2725 950);
DISPLAY 1.021277 (2725 950);
DISPLAY INVISIBLE (2725 950);
FORCEADD OFFPAGE..5
R 2
(2275 1000);
FORCEPROP 2 LAST $XR2 301 
J 0
(2704 1000);
DISPLAY 0.638298 (2704 1000);
PAINT MONO (2704 1000);
FORCEPROP 2 LAST $XR1 303 
J 0
(2584 1000);
DISPLAY 0.638298 (2584 1000);
PAINT MONO (2584 1000);
FORCEPROP 2 LAST $XR0 302 
J 0
(2464 1000);
DISPLAY 0.638298 (2464 1000);
PAINT MONO (2464 1000);
FORCEPROP 2 LAST CDS_LIB standard
J 2
(2275 1000);
DISPLAY INVISIBLE (2275 1000);
FORCEPROP 1 LAST OFFPAGE TRUE
J 2
(1950 875);
DISPLAY 0.872340 (1950 875);
PAINT AQUA (1950 875);
DISPLAY INVISIBLE (1950 875);
FORCEPROP 1 LAST COMMENT_BODY TRUE
J 2
(2175 925);
DISPLAY 1.170213 (2175 925);
PAINT GREEN (2175 925);
DISPLAY INVISIBLE (2175 925);
FORCEPROP 2 LAST PATH I53
J 0
(2725 1050);
DISPLAY 1.021277 (2725 1050);
DISPLAY INVISIBLE (2725 1050);
FORCEADD OFFPAGE..5
R 2
(2275 1100);
FORCEPROP 2 LAST $XR2 301 
J 0
(2704 1100);
DISPLAY 0.638298 (2704 1100);
PAINT MONO (2704 1100);
FORCEPROP 2 LAST $XR1 303 
J 0
(2584 1100);
DISPLAY 0.638298 (2584 1100);
PAINT MONO (2584 1100);
FORCEPROP 2 LAST $XR0 302 
J 0
(2464 1100);
DISPLAY 0.638298 (2464 1100);
PAINT MONO (2464 1100);
FORCEPROP 2 LAST CDS_LIB standard
J 2
(2275 1100);
DISPLAY INVISIBLE (2275 1100);
FORCEPROP 1 LAST OFFPAGE TRUE
J 2
(1950 975);
DISPLAY 0.872340 (1950 975);
PAINT AQUA (1950 975);
DISPLAY INVISIBLE (1950 975);
FORCEPROP 1 LAST COMMENT_BODY TRUE
J 2
(2175 1025);
DISPLAY 1.170213 (2175 1025);
PAINT GREEN (2175 1025);
DISPLAY INVISIBLE (2175 1025);
FORCEPROP 2 LAST PATH I54
J 0
(2725 1150);
DISPLAY 1.021277 (2725 1150);
DISPLAY INVISIBLE (2725 1150);
FORCEADD OFFPAGE..4
(2275 1300);
FORCEPROP 2 LAST $XR2 303 
J 0
(2701 1300);
DISPLAY 0.638298 (2701 1300);
PAINT MONO (2701 1300);
FORCEPROP 2 LAST $XR1 302 
J 0
(2581 1300);
DISPLAY 0.638298 (2581 1300);
PAINT MONO (2581 1300);
FORCEPROP 2 LAST $XR0 301 
J 0
(2461 1300);
DISPLAY 0.638298 (2461 1300);
PAINT MONO (2461 1300);
FORCEPROP 2 LAST CDS_LIB standard
J 0
(2275 1300);
DISPLAY INVISIBLE (2275 1300);
FORCEPROP 1 LAST OFFPAGE TRUE
J 0
(2600 1175);
DISPLAY 0.872340 (2600 1175);
PAINT GREEN (2600 1175);
DISPLAY INVISIBLE (2600 1175);
FORCEPROP 1 LAST COMMENT_BODY TRUE
J 0
(2250 1200);
DISPLAY 0.872340 (2250 1200);
PAINT GREEN (2250 1200);
DISPLAY INVISIBLE (2250 1200);
FORCEPROP 2 LAST PATH I55
J 0
(2725 1350);
DISPLAY 1.021277 (2725 1350);
DISPLAY INVISIBLE (2725 1350);
FORCEADD OFFPAGE..5
R 2
(2275 1475);
FORCEPROP 2 LAST $XR2 301 
J 0
(2704 1475);
DISPLAY 0.638298 (2704 1475);
PAINT MONO (2704 1475);
FORCEPROP 2 LAST $XR1 303 
J 0
(2584 1475);
DISPLAY 0.638298 (2584 1475);
PAINT MONO (2584 1475);
FORCEPROP 2 LAST $XR0 302 
J 0
(2464 1475);
DISPLAY 0.638298 (2464 1475);
PAINT MONO (2464 1475);
FORCEPROP 2 LAST CDS_LIB standard
J 0
(2275 1475);
DISPLAY INVISIBLE (2275 1475);
FORCEPROP 1 LAST OFFPAGE TRUE
J 2
(1950 1350);
DISPLAY 0.872340 (1950 1350);
PAINT AQUA (1950 1350);
DISPLAY INVISIBLE (1950 1350);
FORCEPROP 1 LAST COMMENT_BODY TRUE
J 2
(2175 1400);
DISPLAY 1.170213 (2175 1400);
PAINT GREEN (2175 1400);
DISPLAY INVISIBLE (2175 1400);
FORCEPROP 2 LAST PATH I56
J 0
(2725 1525);
DISPLAY 1.021277 (2725 1525);
DISPLAY INVISIBLE (2725 1525);
FORCEADD UNIVERSAL_POWER..1
(-3475 -700);
FORCEPROP 3 LASTPIN (-3475 -750) SIG_NAME HSC_VDD\g
J 0
(-3465 -740);
DISPLAY 0.659574 (-3465 -740);
PAINT MONO (-3465 -740);
DISPLAY INVISIBLE (-3465 -740);
FORCEPROP 1 LAST HDL_POWER HSC_VDD
J 1
(-3475 -650);
DISPLAY 0.723404 (-3475 -650);
PAINT GREEN (-3475 -650);
FORCEPROP 2 LAST ROOM AUX_SW
J 0
(-3475 -600);
DISPLAY 0.617021 (-3475 -600);
FORCEPROP 2 LAST CDS_LIB pure_quanta_power
J 0
(-3475 -700);
DISPLAY INVISIBLE (-3475 -700);
FORCEPROP 2 LAST BOM_COST MIO_VRD_SB
J 0
(-3475 -600);
DISPLAY 0.617021 (-3475 -600);
PAINT PURPLE (-3475 -600);
DISPLAY INVISIBLE (-3475 -600);
FORCEPROP 1 LAST PATH I6
J 0
(-3425 -675);
DISPLAY 0.872340 (-3425 -675);
PAINT AQUA (-3425 -675);
DISPLAY INVISIBLE (-3425 -675);
FORCEADD OFFPAGE..4
R 2
(-2775 -1550);
FORCEPROP 2 LAST $XR2 303 
J 0
(-3057 -1586);
DISPLAY 0.638298 (-3057 -1586);
PAINT MONO (-3057 -1586);
FORCEPROP 2 LAST $XR1 302 
J 0
(-3177 -1550);
DISPLAY 0.638298 (-3177 -1550);
PAINT MONO (-3177 -1550);
FORCEPROP 2 LAST $XR0 301 
J 0
(-3057 -1550);
DISPLAY 0.638298 (-3057 -1550);
PAINT MONO (-3057 -1550);
FORCEPROP 2 LAST CDS_LIB standard
J 0
(-2775 -1550);
DISPLAY INVISIBLE (-2775 -1550);
FORCEPROP 1 LAST OFFPAGE TRUE
J 2
(-3100 -1675);
DISPLAY 0.872340 (-3100 -1675);
PAINT GREEN (-3100 -1675);
DISPLAY INVISIBLE (-3100 -1675);
FORCEPROP 1 LAST COMMENT_BODY TRUE
J 2
(-2750 -1650);
DISPLAY 0.872340 (-2750 -1650);
PAINT GREEN (-2750 -1650);
DISPLAY INVISIBLE (-2750 -1650);
FORCEPROP 2 LAST PATH I7
J 0
(-3050 -1500);
DISPLAY 1.021277 (-3050 -1500);
DISPLAY INVISIBLE (-3050 -1500);
FORCEADD UNIVERSAL_GND..1
(-2725 -1350);
FORCEPROP 3 LASTPIN (-2725 -1300) SIG_NAME AGND_HSC\g
J 0
(-2715 -1290);
DISPLAY 0.659574 (-2715 -1290);
PAINT MONO (-2715 -1290);
DISPLAY INVISIBLE (-2715 -1290);
FORCEPROP 1 LAST HDL_POWER AGND_HSC
J 1
(-2700 -1425);
DISPLAY 0.723404 (-2700 -1425);
PAINT GREEN (-2700 -1425);
FORCEPROP 2 LAST CDS_LIB pure_quanta_power
J 0
(-2725 -1350);
DISPLAY INVISIBLE (-2725 -1350);
FORCEPROP 1 LAST PATH I8
J 0
(-2650 -1350);
DISPLAY 0.872340 (-2650 -1350);
PAINT AQUA (-2650 -1350);
DISPLAY INVISIBLE (-2650 -1350);
FORCEADD OFFPAGE..4
R 2
(-2100 -1650);
FORCEPROP 2 LAST $XR2 303 
J 0
(-2622 -1650);
DISPLAY 0.638298 (-2622 -1650);
PAINT MONO (-2622 -1650);
FORCEPROP 2 LAST $XR1 302 
J 0
(-2502 -1650);
DISPLAY 0.638298 (-2502 -1650);
PAINT MONO (-2502 -1650);
FORCEPROP 2 LAST $XR0 301 
J 0
(-2382 -1650);
DISPLAY 0.638298 (-2382 -1650);
PAINT MONO (-2382 -1650);
FORCEPROP 2 LAST CDS_LIB standard
J 0
(-2100 -1650);
DISPLAY INVISIBLE (-2100 -1650);
FORCEPROP 1 LAST OFFPAGE TRUE
J 2
(-2425 -1775);
DISPLAY 0.872340 (-2425 -1775);
PAINT GREEN (-2425 -1775);
DISPLAY INVISIBLE (-2425 -1775);
FORCEPROP 1 LAST COMMENT_BODY TRUE
J 2
(-2075 -1750);
DISPLAY 0.872340 (-2075 -1750);
PAINT GREEN (-2075 -1750);
DISPLAY INVISIBLE (-2075 -1750);
FORCEPROP 2 LAST PATH I9
J 0
(-2375 -1600);
DISPLAY 1.021277 (-2375 -1600);
DISPLAY INVISIBLE (-2375 -1600);
FORCEADD QUANTA_TITLE_BLOCK_C..1
(4700 -3250);
FORCEPROP 0 LAST CDS_CON_LAST_MODIFIED Fri Mar 11 14:53:40 2022
J 0
(2815 -3235);
PAINT MONO (2815 -3235);
DISPLAY INVISIBLE (2815 -3235);
FORCEPROP 2 LAST CUSTOM_TXT_CDS <XR_PAGE_TITLE>
J 0
(-3190 2000);
DISPLAY 0.638298 (-3190 2000);
PAINT PINK (-3190 2000);
DISPLAY INVISIBLE (-3190 2000);
FORCEPROP 2 LAST CUSTOM_TXT_CDS <CON_LAST_MODIFIED>
J 0
(2815 -3235);
DISPLAY 0.978723 (2815 -3235);
FORCEPROP 2 LAST CUSTOM_TXT_CDS <Q_REV>
J 0
(4516 -3147);
DISPLAY 1.212766 (4516 -3147);
FORCEPROP 2 LAST CUSTOM_TXT_CDS <CON_PAGE_NUM> OF <CON_TOTAL_PAGES>
J 0
(4254 -3232);
DISPLAY 0.978723 (4254 -3232);
FORCEPROP 2 LAST CUSTOM_TXT_CDS <Q_PROJ>
J 0
(2318 -3148);
DISPLAY 1.212766 (2318 -3148);
FORCEPROP 2 LAST CUSTOM_TXT_CDS <Q_NUMBER>
J 0
(3297 -3147);
DISPLAY 1.212766 (3297 -3147);
FORCEPROP 1 LAST CUSTOM_TXT_CDS <NAME_2>
J 0
(1525 -3200);
FORCEPROP 1 LAST CUSTOM_TXT_CDS <NAME_1>
J 0
(1525 -3075);
FORCEPROP 1 LAST Q_DEPT BU9
J 1
(937 -3201);
DISPLAY 1.957447 (937 -3201);
PAINT GREEN (937 -3201);
FORCEPROP 1 LAST Q_TITLE HSC MP5990 (2/4)
J 0
(-4666 -3224);
DISPLAY 2.446809 (-4666 -3224);
PAINT GREEN (-4666 -3224);
FORCEPROP 1 LAST CDS_LMAN_SYM_OUTLINE -9475,6775,100,-125
J 0
(4700 -3250);
DISPLAY 0.468085 (4700 -3250);
PAINT GREEN (4700 -3250);
DISPLAY INVISIBLE (4700 -3250);
FORCEPROP 2 LAST CDS_LIB pure_quanta
J 0
(4700 -3250);
PAINT MONO (4700 -3250);
DISPLAY INVISIBLE (4700 -3250);
FORCEPROP 2 LAST PAGE_BORDER TRUE
J 0
(-3190 2000);
DISPLAY 0.638298 (-3190 2000);
PAINT PINK (-3190 2000);
DISPLAY INVISIBLE (-3190 2000);
FORCEPROP 1 LAST COMMENT_BODY TRUE
J 0
(4712 -3263);
DISPLAY 0.978723 (4712 -3263);
PAINT GREEN (4712 -3263);
DISPLAY INVISIBLE (4712 -3263);
FORCEPROP 2 LAST CDS_XR_PAGE_TITLE CR-302 : @S9S_MB_2U_LIB.S9S_MB_2U(SCH_1):PAGE302
J 0
(-3190 2000);
DISPLAY 0.638298 (-3190 2000);
PAINT PINK (-3190 2000);
DISPLAY INVISIBLE (-3190 2000);
FORCEADD DNS..2
(-2650 -2100);
PAINT RED (-2650 -2100);
FORCEPROP 2 LAST CDS_LIB mstr_misc
J 0
(-2650 -2100);
DISPLAY INVISIBLE (-2650 -2100);
FORCEPROP 1 LAST COMMENT_BODY TRUE
R 1
J 0
(-2575 -2325);
DISPLAY 0.872340 (-2575 -2325);
PAINT GREEN (-2575 -2325);
DISPLAY INVISIBLE (-2575 -2325);
FORCEADD DNS..2
(-1950 -2075);
PAINT RED (-1950 -2075);
FORCEPROP 2 LAST CDS_LIB mstr_misc
J 0
(-1950 -2075);
DISPLAY INVISIBLE (-1950 -2075);
FORCEPROP 1 LAST COMMENT_BODY TRUE
R 1
J 0
(-1875 -2300);
DISPLAY 0.872340 (-1875 -2300);
PAINT GREEN (-1875 -2300);
DISPLAY INVISIBLE (-1875 -2300);
FORCEADD DNS..2
(-1975 725);
PAINT RED (-1975 725);
FORCEPROP 2 LAST CDS_LIB mstr_misc
J 0
(-1975 725);
DISPLAY INVISIBLE (-1975 725);
FORCEPROP 1 LAST COMMENT_BODY TRUE
R 1
J 0
(-1900 500);
DISPLAY 0.872340 (-1900 500);
PAINT GREEN (-1900 500);
DISPLAY INVISIBLE (-1900 500);
WIRE 16 -1 (-3450 1275)(-3450 1125);
WIRE 16 -1 (-3450 2050)(-3450 1950);
WIRE 16 -1 (-3475 -1525)(-3475 -1675);
WIRE 16 -1 (975 -2150)(975 -2225);
WIRE 16 -1 (975 650)(975 575);
WIRE 16 -1 (-3475 -750)(-3475 -850);
WIRE 16 -1 (1575 1300)(2225 1300);
FORCEPROP 2 LAST SIG_NAME HSC_FLT_TYPE
J 0
(1715 1310);
DISPLAY 0.808511 (1715 1310);
WIRE 16 -1 (1575 1475)(2225 1475);
FORCEPROP 2 LAST SIG_NAME HSC_D_OC_R
J 0
(1790 1485);
DISPLAY 0.808511 (1790 1485);
WIRE 16 -1 (475 1000)(2225 1000);
FORCEPROP 2 LAST SIG_NAME HSC_VTEMP
J 0
(590 1010);
DISPLAY 0.808511 (590 1010);
WIRE 16 -1 (475 1100)(2225 1100);
FORCEPROP 2 LAST SIG_NAME HSC_FAULT
J 0
(590 1110);
DISPLAY 0.808511 (590 1110);
WIRE 16 -1 (1100 2300)(1100 2275);
WIRE 16 -1 (1100 2275)(600 2275);
WIRE 16 -1 (600 2275)(600 2200);
WIRE 16 -1 (475 2200)(600 2200);
WIRE 16 -1 (600 2200)(600 2150);
WIRE 16 -1 (475 2150)(600 2150);
WIRE 16 -1 (600 2150)(600 2100);
WIRE 16 -1 (475 2100)(600 2100);
WIRE 16 -1 (600 2100)(600 2050);
WIRE 16 -1 (600 2050)(600 2000);
WIRE 16 -1 (475 2050)(600 2050);
WIRE 16 -1 (600 2000)(600 1950);
WIRE 16 -1 (475 2000)(600 2000);
WIRE 16 -1 (600 1950)(600 1900);
WIRE 16 -1 (475 1950)(600 1950);
WIRE 16 -1 (600 1900)(600 1850);
WIRE 16 -1 (475 1900)(600 1900);
WIRE 16 -1 (600 1850)(600 1800);
WIRE 16 -1 (475 1850)(600 1850);
WIRE 16 -1 (600 1800)(600 1750);
WIRE 16 -1 (475 1800)(600 1800);
WIRE 16 -1 (600 1750)(475 1750);
WIRE 16 -1 (475 1300)(1375 1300);
FORCEPROP 2 LAST SIG_NAME HSC_FLT_TYPE_1
J 0
(590 1310);
DISPLAY 0.808511 (590 1310);
WIRE 16 -1 (600 1475)(1375 1475);
WIRE 16 -1 (600 1400)(600 1475);
FORCEPROP 2 LAST SIG_NAME HSC_D_OC_1
J 0
(590 1485);
DISPLAY 0.808511 (590 1485);
WIRE 16 -1 (600 1400)(475 1400);
WIRE 16 -1 (475 1200)(925 1200);
FORCEPROP 2 LAST SIG_NAME HSC_NC1_1
J 0
(590 1210);
DISPLAY 0.808511 (590 1210);
WIRE 16 -1 (975 900)(2225 900);
WIRE 16 -1 (975 900)(975 850);
WIRE 16 -1 (475 900)(975 900);
FORCEPROP 2 LAST SIG_NAME HSC_SS
J 0
(590 910);
DISPLAY 0.808511 (590 910);
WIRE 16 -1 (1575 -1325)(2200 -1325);
FORCEPROP 2 LAST SIG_NAME HSC_D_OC_R
J 0
(1740 -1315);
DISPLAY 0.808511 (1740 -1315);
WIRE 16 -1 (475 -1800)(2200 -1800);
FORCEPROP 2 LAST SIG_NAME HSC_VTEMP
J 0
(565 -1790);
DISPLAY 0.808511 (565 -1790);
WIRE 16 -1 (1575 -1500)(2200 -1500);
FORCEPROP 2 LAST SIG_NAME HSC_FLT_TYPE
J 0
(1690 -1490);
DISPLAY 0.808511 (1690 -1490);
WIRE 16 -1 (475 -1700)(2200 -1700);
FORCEPROP 2 LAST SIG_NAME HSC_FAULT
J 0
(565 -1690);
DISPLAY 0.808511 (565 -1690);
WIRE 16 -1 (475 -1500)(1375 -1500);
FORCEPROP 2 LAST SIG_NAME HSC_FLT_TYPE_2
J 0
(565 -1490);
DISPLAY 0.808511 (565 -1490);
WIRE 16 -1 (1100 -500)(1100 -525);
WIRE 16 -1 (1100 -525)(600 -525);
WIRE 16 -1 (600 -525)(600 -600);
WIRE 16 -1 (475 -600)(600 -600);
WIRE 16 -1 (600 -600)(600 -650);
WIRE 16 -1 (475 -650)(600 -650);
WIRE 16 -1 (600 -650)(600 -700);
WIRE 16 -1 (475 -700)(600 -700);
WIRE 16 -1 (600 -700)(600 -750);
WIRE 16 -1 (600 -750)(600 -800);
WIRE 16 -1 (475 -750)(600 -750);
WIRE 16 -1 (600 -800)(600 -850);
WIRE 16 -1 (475 -800)(600 -800);
WIRE 16 -1 (600 -850)(600 -900);
WIRE 16 -1 (475 -850)(600 -850);
WIRE 16 -1 (600 -900)(600 -950);
WIRE 16 -1 (475 -900)(600 -900);
WIRE 16 -1 (600 -950)(600 -1000);
WIRE 16 -1 (475 -950)(600 -950);
WIRE 16 -1 (600 -1000)(600 -1050);
WIRE 16 -1 (475 -1000)(600 -1000);
WIRE 16 -1 (600 -1050)(475 -1050);
WIRE 16 -1 (550 -1325)(1375 -1325);
WIRE 16 -1 (550 -1400)(550 -1325);
FORCEPROP 2 LAST SIG_NAME HSC_D_OC_2
J 0
(565 -1315);
DISPLAY 0.808511 (565 -1315);
WIRE 16 -1 (550 -1400)(475 -1400);
WIRE 16 -1 (475 -1600)(925 -1600);
FORCEPROP 2 LAST SIG_NAME HSC_NC1_2
J 0
(590 -1590);
DISPLAY 0.808511 (590 -1590);
WIRE 16 -1 (975 -1900)(2200 -1900);
WIRE 16 -1 (975 -1900)(975 -1950);
WIRE 16 -1 (475 -1900)(975 -1900);
FORCEPROP 2 LAST SIG_NAME HSC_SS
J 0
(565 -1890);
DISPLAY 0.808511 (565 -1890);
WIRE 16 -1 (-975 2300)(-975 2250);
WIRE 16 -1 (-975 2250)(-675 2250);
WIRE 16 -1 (-675 2250)(-675 2200);
WIRE 16 -1 (-475 2200)(-675 2200);
WIRE 16 -1 (-675 2200)(-675 2150);
WIRE 16 -1 (-475 2150)(-675 2150);
WIRE 16 -1 (-675 2150)(-675 2100);
WIRE 16 -1 (-475 2100)(-675 2100);
WIRE 16 -1 (-675 2100)(-675 2050);
WIRE 16 -1 (-475 2050)(-675 2050);
WIRE 16 -1 (-675 2050)(-675 2000);
WIRE 16 -1 (-475 2000)(-675 2000);
WIRE 16 -1 (-675 2000)(-675 1950);
WIRE 16 -1 (-475 1950)(-675 1950);
WIRE 16 -1 (-675 1950)(-675 1900);
WIRE 16 -1 (-475 1900)(-675 1900);
WIRE 16 -1 (-675 1900)(-675 1850);
WIRE 16 -1 (-475 1850)(-675 1850);
WIRE 16 -1 (-675 1850)(-675 1800);
WIRE 16 -1 (-675 1800)(-475 1800);
WIRE 16 -1 (-900 1450)(-900 1375);
WIRE 16 -1 (-475 1450)(-900 1450);
FORCEPROP 2 LAST SIG_NAME HSC_SCREF_1
J 0
(-1035 1460);
DISPLAY 0.808511 (-1035 1460);
WIRE 16 -1 (-900 1375)(-1250 1375);
WIRE 16 -1 (-475 750)(-525 750);
WIRE 16 -1 (-525 750)(-525 550);
WIRE 16 -1 (-975 550)(-525 550);
WIRE 16 -1 (-975 625)(-975 550);
WIRE 16 -1 (-975 550)(-1500 550);
WIRE 16 -1 (-1500 625)(-1500 550);
WIRE 16 -1 (-2000 550)(-1500 550);
WIRE 16 -1 (-2000 550)(-2675 550);
WIRE 16 -1 (-2000 625)(-2000 550);
WIRE 16 -1 (-2675 475)(-2675 550);
WIRE 16 -1 (-2675 625)(-2675 550);
WIRE 16 -1 (-975 825)(-975 950);
WIRE 16 -1 (-475 950)(-975 950);
FORCEPROP 2 LAST SIG_NAME HSC_IMON
J 0
(-1035 960);
DISPLAY 0.808511 (-1035 960);
WIRE 16 -1 (-1025 950)(-975 950);
WIRE 16 -1 (-1825 1550)(-475 1550);
FORCEPROP 2 LAST SIG_NAME HSC_MODE_1
J 0
(-1035 1560);
DISPLAY 0.808511 (-1035 1560);
WIRE 16 -1 (-1450 1375)(-2000 1375);
FORCEPROP 2 LAST SIG_NAME HSC_SCREF
J 0
(-2010 1385);
DISPLAY 0.808511 (-2010 1385);
WIRE 16 -1 (-475 1050)(-1500 1050);
FORCEPROP 2 LAST SIG_NAME HSC_CS_1
J 0
(-1035 1060);
DISPLAY 0.808511 (-1035 1060);
WIRE 16 -1 (-1500 1050)(-1500 825);
WIRE 16 -1 (-2000 825)(-2000 1150);
WIRE 16 -1 (-475 1150)(-2000 1150);
FORCEPROP 2 LAST SIG_NAME HSC_OCREF
J 0
(-1035 1160);
DISPLAY 0.808511 (-1035 1160);
WIRE 16 -1 (-2100 1150)(-2000 1150);
WIRE 16 -1 (-2625 1525)(-2625 1550);
WIRE 16 -1 (-2625 1550)(-2025 1550);
WIRE 16 -1 (-475 1250)(-2675 1250);
FORCEPROP 2 LAST SIG_NAME HSC_ON
J 0
(-1035 1260);
DISPLAY 0.808511 (-1035 1260);
WIRE 16 -1 (-2725 1250)(-2675 1250);
WIRE 16 -1 (-2675 1250)(-2675 825);
WIRE 16 -1 (-3450 1750)(-3450 1650);
WIRE 16 -1 (-3450 1650)(-475 1650);
FORCEPROP 2 LAST SIG_NAME HSC_VDD_R_1
J 0
(-1035 1660);
DISPLAY 0.808511 (-1035 1660);
WIRE 16 -1 (-3450 1475)(-3450 1650);
WIRE 16 -1 (-975 -500)(-975 -550);
WIRE 16 -1 (-975 -550)(-675 -550);
WIRE 16 -1 (-675 -550)(-675 -600);
WIRE 16 -1 (-475 -600)(-675 -600);
WIRE 16 -1 (-675 -600)(-675 -650);
WIRE 16 -1 (-475 -650)(-675 -650);
WIRE 16 -1 (-675 -650)(-675 -700);
WIRE 16 -1 (-475 -700)(-675 -700);
WIRE 16 -1 (-675 -700)(-675 -750);
WIRE 16 -1 (-475 -750)(-675 -750);
WIRE 16 -1 (-675 -750)(-675 -800);
WIRE 16 -1 (-475 -800)(-675 -800);
WIRE 16 -1 (-675 -800)(-675 -850);
WIRE 16 -1 (-475 -850)(-675 -850);
WIRE 16 -1 (-675 -850)(-675 -900);
WIRE 16 -1 (-475 -900)(-675 -900);
WIRE 16 -1 (-675 -900)(-675 -950);
WIRE 16 -1 (-475 -950)(-675 -950);
WIRE 16 -1 (-675 -950)(-675 -1000);
WIRE 16 -1 (-675 -1000)(-475 -1000);
WIRE 16 -1 (-900 -1350)(-900 -1425);
WIRE 16 -1 (-475 -1350)(-900 -1350);
FORCEPROP 2 LAST SIG_NAME HSC_SCREF_2
J 0
(-1010 -1340);
DISPLAY 0.808511 (-1010 -1340);
WIRE 16 -1 (-900 -1425)(-1225 -1425);
WIRE 16 -1 (-1825 -1250)(-475 -1250);
FORCEPROP 2 LAST SIG_NAME HSC_MODE_2
J 0
(-1010 -1240);
DISPLAY 0.808511 (-1010 -1240);
WIRE 16 -1 (-1425 -1425)(-2000 -1425);
FORCEPROP 2 LAST SIG_NAME HSC_SCREF
J 0
(-2010 -1415);
DISPLAY 0.808511 (-2010 -1415);
WIRE 16 -1 (-475 -1750)(-1500 -1750);
FORCEPROP 2 LAST SIG_NAME HSC_CS_2
J 0
(-1010 -1740);
DISPLAY 0.808511 (-1010 -1740);
WIRE 16 -1 (-1500 -1750)(-1500 -1975);
WIRE 16 -1 (-1025 -1850)(-975 -1850);
WIRE 16 -1 (-475 -1850)(-975 -1850);
FORCEPROP 2 LAST SIG_NAME HSC_IMON
J 0
(-1010 -1840);
DISPLAY 0.808511 (-1010 -1840);
WIRE 16 -1 (-975 -1975)(-975 -1850);
WIRE 16 -1 (-475 -2050)(-525 -2050);
WIRE 16 -1 (-525 -2050)(-525 -2250);
WIRE 16 -1 (-975 -2250)(-525 -2250);
WIRE 16 -1 (-975 -2175)(-975 -2250);
WIRE 16 -1 (-975 -2250)(-1500 -2250);
WIRE 16 -1 (-1500 -2175)(-1500 -2250);
WIRE 16 -1 (-1975 -2250)(-1500 -2250);
WIRE 16 -1 (-1975 -2250)(-2650 -2250);
WIRE 16 -1 (-1975 -2175)(-1975 -2250);
WIRE 16 -1 (-2650 -2350)(-2650 -2250);
WIRE 16 -1 (-2650 -2175)(-2650 -2250);
WIRE 16 -1 (-1975 -1975)(-1975 -1650);
WIRE 16 -1 (-475 -1650)(-1975 -1650);
FORCEPROP 2 LAST SIG_NAME HSC_OCREF
J 0
(-1010 -1640);
DISPLAY 0.808511 (-1010 -1640);
WIRE 16 -1 (-2050 -1650)(-1975 -1650);
WIRE 16 -1 (-2725 -1300)(-2725 -1250);
WIRE 16 -1 (-2725 -1250)(-2025 -1250);
WIRE 16 -1 (-3475 -1050)(-3475 -1150);
WIRE 16 -1 (-3475 -1150)(-475 -1150);
FORCEPROP 2 LAST SIG_NAME HSC_VDD_R_2
J 0
(-1010 -1140);
DISPLAY 0.808511 (-1010 -1140);
WIRE 16 -1 (-3475 -1325)(-3475 -1150);
WIRE 16 -1 (-475 -1550)(-2650 -1550);
FORCEPROP 2 LAST SIG_NAME HSC_ON
J 0
(-1010 -1540);
DISPLAY 0.808511 (-1010 -1540);
WIRE 16 -1 (-2725 -1550)(-2650 -1550);
WIRE 16 -1 (-2650 -1550)(-2650 -1975);
DOT 1 (600 2200);
DOT 1 (600 2150);
DOT 1 (600 2100);
DOT 1 (600 2000);
DOT 1 (600 2050);
DOT 1 (600 1950);
DOT 1 (600 1900);
DOT 1 (600 1850);
DOT 1 (600 1800);
DOT 1 (975 900);
DOT 1 (600 -700);
DOT 1 (600 -600);
DOT 1 (600 -650);
DOT 1 (600 -800);
DOT 1 (600 -750);
DOT 1 (600 -950);
DOT 1 (600 -850);
DOT 1 (600 -900);
DOT 1 (600 -1000);
DOT 1 (975 -1900);
DOT 1 (-675 2150);
DOT 1 (-675 2200);
DOT 1 (-675 2100);
DOT 1 (-675 2000);
DOT 1 (-675 2050);
DOT 1 (-675 1950);
DOT 1 (-675 1900);
DOT 1 (-675 1850);
DOT 1 (-975 950);
DOT 1 (-975 550);
DOT 1 (-1500 550);
DOT 1 (-2000 1150);
DOT 1 (-2000 550);
DOT 1 (-2675 1250);
DOT 1 (-2675 550);
DOT 1 (-3450 1650);
DOT 1 (-675 -650);
DOT 1 (-675 -600);
DOT 1 (-675 -700);
DOT 1 (-675 -800);
DOT 1 (-675 -750);
DOT 1 (-675 -900);
DOT 1 (-675 -950);
DOT 1 (-675 -850);
DOT 1 (-975 -1850);
DOT 1 (-1975 -1650);
DOT 1 (-975 -2250);
DOT 1 (-1500 -2250);
DOT 1 (-1975 -2250);
DOT 1 (-2650 -1550);
DOT 1 (-3475 -1150);
DOT 1 (-2650 -2250);
FORCENOTE
SOFT START TIME=6MS.
(1475 691) 0;
DISPLAY LEFT (1475 691);
DISPLAY 1.021277 (1475 691);
FORCENOTE
VOUT SLEW RATE: 2V/MS
(1475 625) 0;
DISPLAY LEFT (1475 625);
DISPLAY 1.021277 (1475 625);
FORCENOTE
SOFT START TIME=6MS.
(1475 -2110) 0;
DISPLAY LEFT (1475 -2110);
DISPLAY 1.021277 (1475 -2110);
FORCENOTE
VOUT SLEW RATE: 2V/MS
(1475 -2175) 0;
DISPLAY LEFT (1475 -2175);
DISPLAY 1.021277 (1475 -2175);
FORCENOTE
20211112 MODIFY FOR GT
(-1350 3150) 0;
DISPLAY LEFT (-1350 3150);
DISPLAY 2.510638 (-1350 3150);
PAINT PINK (-1350 3150);
FORCENOTE
CHANGE PU288 TO AL005981A00
(-675 -2675) 0;
DISPLAY LEFT (-675 -2675);
DISPLAY 1.021277 (-675 -2675);
FORCENOTE
DNI PR3917, PR3921, PR3922
(-675 -2610) 0;
DISPLAY LEFT (-675 -2610);
DISPLAY 1.021277 (-675 -2610);
FORCENOTE
DNI PR3919, PR3920, PR3916
(-675 285) 0;
DISPLAY LEFT (-675 285);
DISPLAY 1.021277 (-675 285);
FORCENOTE
CHANGE PU287 TO AL005981A00
(-675 220) 0;
DISPLAY LEFT (-675 220);
DISPLAY 1.021277 (-675 220);
FORCENOTE
FOR MP5981:
(-675 350) 0;
DISPLAY LEFT (-675 350);
DISPLAY 1.021277 (-675 350);
FORCENOTE
STILL NEED TO CHANGE TO EF PART
(-1475 425) 0;
DISPLAY LEFT (-1475 425);
DISPLAY 1.021277 (-1475 425);
FORCENOTE
PR3914,PR3918
(-1475 500) 0;
DISPLAY LEFT (-1475 500);
DISPLAY 1.021277 (-1475 500);
FORCENOTE
FPH=220A
(-3800 3009) 0;
DISPLAY LEFT (-3800 3009);
DISPLAY 1.595745 (-3800 3009);
FORCENOTE
OV =14.333V
(-4500 2925) 0;
DISPLAY LEFT (-4500 2925);
DISPLAY 1.021277 (-4500 2925);
FORCENOTE
UV =10.091V
(-4500 2875) 0;
DISPLAY LEFT (-4500 2875);
DISPLAY 1.021277 (-4500 2875);
FORCENOTE
OCW=220A
(-4525 3009) 0;
DISPLAY LEFT (-4525 3009);
DISPLAY 1.595745 (-4525 3009);
FORCENOTE
ADDRESS 0X20
(-4500 2816) 0;
DISPLAY LEFT (-4500 2816);
DISPLAY 1.021277 (-4500 2816);
FORCENOTE
LATCH OFF MODE
(-4500 2750) 0;
DISPLAY LEFT (-4500 2750);
DISPLAY 1.021277 (-4500 2750);
FORCENOTE
OCP=240A
(-4525 3084) 0;
DISPLAY LEFT (-4525 3084);
DISPLAY 1.595745 (-4525 3084);
FORCENOTE
HOT SWAT CIRCUIT
(-4521 3188) 0;
DISPLAY LEFT (-4521 3188);
DISPLAY 2.000000 (-4521 3188);
FORCENOTE
FOR MP5981:
(-675 -2545) 0;
DISPLAY LEFT (-675 -2545);
DISPLAY 1.021277 (-675 -2545);
QUIT
